(kicad_sch
	(version 20250114)
	(generator "eeschema")
	(generator_version "9.0")
	(paper "A3")
	(title_block
		(title "DDR5 testbed")
		(date "2024-05-27")
		(rev "1.1.2")
		(comment 1 "www.antmicro.com")
		(comment 2 "Antmicro Ltd.")
	)
	(text "DDR5 DRAM IC"
		(exclude_from_sim no)
		(at 27.305 26.035 0)
		(effects
			(font
				(size 2.4892 2.4892)
				(thickness 0.4978)
				(bold yes)
			)
			(justify left bottom)
		)
	)
	(junction
		(at 226.695 121.92)
		(diameter 0)
		(color 0 0 0 0)
	)
	(junction
		(at 149.86 137.16)
		(diameter 0)
		(color 0 0 0 0)
	)
	(junction
		(at 224.155 104.775)
		(diameter 0)
		(color 0 0 0 0)
	)
	(junction
		(at 224.155 124.46)
		(diameter 0)
		(color 0 0 0 0)
	)
	(wire
		(pts
			(xy 208.915 170.18) (xy 216.535 170.18)
		)
		(stroke
			(width 0)
			(type default)
		)
	)
	(wire
		(pts
			(xy 170.815 152.4) (xy 163.195 152.4)
		)
		(stroke
			(width 0)
			(type default)
		)
	)
	(wire
		(pts
			(xy 276.86 102.87) (xy 276.86 105.41)
		)
		(stroke
			(width 0)
			(type default)
		)
	)
	(wire
		(pts
			(xy 265.43 105.41) (xy 265.43 102.87)
		)
		(stroke
			(width 0)
			(type default)
		)
	)
	(wire
		(pts
			(xy 238.125 124.46) (xy 245.11 124.46)
		)
		(stroke
			(width 0)
			(type default)
		)
	)
	(wire
		(pts
			(xy 210.82 189.23) (xy 210.82 182.88)
		)
		(stroke
			(width 0)
			(type default)
		)
	)
	(wire
		(pts
			(xy 189.865 68.58) (xy 203.2 68.58)
		)
		(stroke
			(width 0)
			(type default)
		)
	)
	(wire
		(pts
			(xy 210.82 182.88) (xy 208.915 182.88)
		)
		(stroke
			(width 0)
			(type default)
		)
	)
	(wire
		(pts
			(xy 91.44 79.375) (xy 87.63 79.375)
		)
		(stroke
			(width 0)
			(type default)
		)
	)
	(wire
		(pts
			(xy 224.155 104.775) (xy 224.155 109.855)
		)
		(stroke
			(width 0)
			(type default)
		)
	)
	(wire
		(pts
			(xy 155.575 127) (xy 170.815 127)
		)
		(stroke
			(width 0)
			(type default)
		)
	)
	(wire
		(pts
			(xy 91.44 105.41) (xy 91.44 102.87)
		)
		(stroke
			(width 0)
			(type default)
		)
	)
	(wire
		(pts
			(xy 170.815 132.08) (xy 163.195 132.08)
		)
		(stroke
			(width 0)
			(type default)
		)
	)
	(wire
		(pts
			(xy 208.915 147.32) (xy 216.535 147.32)
		)
		(stroke
			(width 0)
			(type default)
		)
	)
	(wire
		(pts
			(xy 190.5 79.375) (xy 194.31 79.375)
		)
		(stroke
			(width 0)
			(type default)
		)
	)
	(wire
		(pts
			(xy 208.915 124.46) (xy 224.155 124.46)
		)
		(stroke
			(width 0)
			(type default)
		)
	)
	(wire
		(pts
			(xy 208.915 157.48) (xy 216.535 157.48)
		)
		(stroke
			(width 0)
			(type default)
		)
	)
	(wire
		(pts
			(xy 149.86 142.24) (xy 149.86 137.16)
		)
		(stroke
			(width 0)
			(type default)
		)
	)
	(wire
		(pts
			(xy 208.915 132.08) (xy 233.045 132.08)
		)
		(stroke
			(width 0)
			(type default)
		)
	)
	(wire
		(pts
			(xy 226.695 104.775) (xy 226.695 109.855)
		)
		(stroke
			(width 0)
			(type default)
		)
	)
	(wire
		(pts
			(xy 246.38 127) (xy 238.125 127)
		)
		(stroke
			(width 0)
			(type default)
		)
	)
	(wire
		(pts
			(xy 236.855 180.34) (xy 246.38 180.34)
		)
		(stroke
			(width 0)
			(type default)
		)
	)
	(wire
		(pts
			(xy 170.815 177.8) (xy 163.195 177.8)
		)
		(stroke
			(width 0)
			(type default)
		)
	)
	(wire
		(pts
			(xy 80.01 81.915) (xy 80.01 79.375)
		)
		(stroke
			(width 0)
			(type default)
		)
	)
	(wire
		(pts
			(xy 238.125 134.62) (xy 246.38 134.62)
		)
		(stroke
			(width 0)
			(type default)
		)
	)
	(wire
		(pts
			(xy 91.44 102.87) (xy 87.63 102.87)
		)
		(stroke
			(width 0)
			(type default)
		)
	)
	(wire
		(pts
			(xy 208.915 129.54) (xy 233.045 129.54)
		)
		(stroke
			(width 0)
			(type default)
		)
	)
	(wire
		(pts
			(xy 303.53 102.87) (xy 309.245 102.87)
		)
		(stroke
			(width 0)
			(type default)
		)
	)
	(wire
		(pts
			(xy 297.815 102.87) (xy 297.815 105.41)
		)
		(stroke
			(width 0)
			(type default)
		)
	)
	(wire
		(pts
			(xy 208.915 177.8) (xy 231.775 177.8)
		)
		(stroke
			(width 0)
			(type default)
		)
	)
	(wire
		(pts
			(xy 224.155 124.46) (xy 233.045 124.46)
		)
		(stroke
			(width 0)
			(type default)
		)
	)
	(wire
		(pts
			(xy 314.325 79.375) (xy 320.04 79.375)
		)
		(stroke
			(width 0)
			(type default)
		)
	)
	(wire
		(pts
			(xy 208.915 160.02) (xy 216.535 160.02)
		)
		(stroke
			(width 0)
			(type default)
		)
	)
	(wire
		(pts
			(xy 287.655 102.87) (xy 287.655 105.41)
		)
		(stroke
			(width 0)
			(type default)
		)
	)
	(wire
		(pts
			(xy 208.915 127) (xy 233.045 127)
		)
		(stroke
			(width 0)
			(type default)
		)
	)
	(wire
		(pts
			(xy 161.925 182.88) (xy 161.925 184.15)
		)
		(stroke
			(width 0)
			(type default)
		)
	)
	(wire
		(pts
			(xy 259.715 79.375) (xy 265.43 79.375)
		)
		(stroke
			(width 0)
			(type default)
		)
	)
	(wire
		(pts
			(xy 170.815 139.7) (xy 163.195 139.7)
		)
		(stroke
			(width 0)
			(type default)
		)
	)
	(wire
		(pts
			(xy 320.04 81.915) (xy 320.04 79.375)
		)
		(stroke
			(width 0)
			(type default)
		)
	)
	(wire
		(pts
			(xy 180.34 79.375) (xy 184.15 79.375)
		)
		(stroke
			(width 0)
			(type default)
		)
	)
	(wire
		(pts
			(xy 170.815 147.32) (xy 163.195 147.32)
		)
		(stroke
			(width 0)
			(type default)
		)
	)
	(wire
		(pts
			(xy 208.915 172.72) (xy 216.535 172.72)
		)
		(stroke
			(width 0)
			(type default)
		)
	)
	(wire
		(pts
			(xy 208.915 180.34) (xy 231.775 180.34)
		)
		(stroke
			(width 0)
			(type default)
		)
	)
	(wire
		(pts
			(xy 170.815 157.48) (xy 163.195 157.48)
		)
		(stroke
			(width 0)
			(type default)
		)
	)
	(wire
		(pts
			(xy 292.1 102.87) (xy 297.815 102.87)
		)
		(stroke
			(width 0)
			(type default)
		)
	)
	(wire
		(pts
			(xy 114.3 105.41) (xy 114.3 102.87)
		)
		(stroke
			(width 0)
			(type default)
		)
	)
	(wire
		(pts
			(xy 87.63 68.58) (xy 97.79 68.58)
		)
		(stroke
			(width 0)
			(type default)
		)
	)
	(wire
		(pts
			(xy 208.915 149.86) (xy 216.535 149.86)
		)
		(stroke
			(width 0)
			(type default)
		)
	)
	(wire
		(pts
			(xy 170.815 180.34) (xy 163.195 180.34)
		)
		(stroke
			(width 0)
			(type default)
		)
	)
	(wire
		(pts
			(xy 184.15 81.915) (xy 184.15 79.375)
		)
		(stroke
			(width 0)
			(type default)
		)
	)
	(wire
		(pts
			(xy 194.31 81.915) (xy 194.31 79.375)
		)
		(stroke
			(width 0)
			(type default)
		)
	)
	(wire
		(pts
			(xy 170.815 142.24) (xy 163.195 142.24)
		)
		(stroke
			(width 0)
			(type default)
		)
	)
	(wire
		(pts
			(xy 102.87 81.915) (xy 102.87 79.375)
		)
		(stroke
			(width 0)
			(type default)
		)
	)
	(wire
		(pts
			(xy 170.815 160.02) (xy 163.195 160.02)
		)
		(stroke
			(width 0)
			(type default)
		)
	)
	(wire
		(pts
			(xy 287.655 79.375) (xy 287.655 81.915)
		)
		(stroke
			(width 0)
			(type default)
		)
	)
	(wire
		(pts
			(xy 114.3 79.375) (xy 110.49 79.375)
		)
		(stroke
			(width 0)
			(type default)
		)
	)
	(wire
		(pts
			(xy 155.575 124.46) (xy 170.815 124.46)
		)
		(stroke
			(width 0)
			(type default)
		)
	)
	(wire
		(pts
			(xy 114.3 102.87) (xy 110.49 102.87)
		)
		(stroke
			(width 0)
			(type default)
		)
	)
	(wire
		(pts
			(xy 208.915 152.4) (xy 216.535 152.4)
		)
		(stroke
			(width 0)
			(type default)
		)
	)
	(wire
		(pts
			(xy 224.155 104.775) (xy 226.695 104.775)
		)
		(stroke
			(width 0)
			(type default)
		)
	)
	(wire
		(pts
			(xy 91.44 81.915) (xy 91.44 79.375)
		)
		(stroke
			(width 0)
			(type default)
		)
	)
	(wire
		(pts
			(xy 215.265 104.775) (xy 224.155 104.775)
		)
		(stroke
			(width 0)
			(type default)
		)
	)
	(wire
		(pts
			(xy 238.125 129.54) (xy 246.38 129.54)
		)
		(stroke
			(width 0)
			(type default)
		)
	)
	(wire
		(pts
			(xy 309.245 102.87) (xy 309.245 105.41)
		)
		(stroke
			(width 0)
			(type default)
		)
	)
	(wire
		(pts
			(xy 80.01 79.375) (xy 76.2 79.375)
		)
		(stroke
			(width 0)
			(type default)
		)
	)
	(wire
		(pts
			(xy 170.815 149.86) (xy 163.195 149.86)
		)
		(stroke
			(width 0)
			(type default)
		)
	)
	(wire
		(pts
			(xy 149.86 137.16) (xy 170.815 137.16)
		)
		(stroke
			(width 0)
			(type default)
		)
	)
	(wire
		(pts
			(xy 208.915 134.62) (xy 233.045 134.62)
		)
		(stroke
			(width 0)
			(type default)
		)
	)
	(wire
		(pts
			(xy 309.245 79.375) (xy 309.245 81.915)
		)
		(stroke
			(width 0)
			(type default)
		)
	)
	(wire
		(pts
			(xy 102.87 79.375) (xy 99.06 79.375)
		)
		(stroke
			(width 0)
			(type default)
		)
	)
	(wire
		(pts
			(xy 125.73 102.87) (xy 121.92 102.87)
		)
		(stroke
			(width 0)
			(type default)
		)
	)
	(wire
		(pts
			(xy 271.145 79.375) (xy 276.86 79.375)
		)
		(stroke
			(width 0)
			(type default)
		)
	)
	(wire
		(pts
			(xy 125.73 81.915) (xy 125.73 79.375)
		)
		(stroke
			(width 0)
			(type default)
		)
	)
	(wire
		(pts
			(xy 80.01 102.87) (xy 76.2 102.87)
		)
		(stroke
			(width 0)
			(type default)
		)
	)
	(wire
		(pts
			(xy 297.815 79.375) (xy 297.815 81.915)
		)
		(stroke
			(width 0)
			(type default)
		)
	)
	(wire
		(pts
			(xy 173.99 68.58) (xy 184.785 68.58)
		)
		(stroke
			(width 0)
			(type default)
		)
	)
	(wire
		(pts
			(xy 170.815 182.88) (xy 161.925 182.88)
		)
		(stroke
			(width 0)
			(type default)
		)
	)
	(wire
		(pts
			(xy 289.56 68.58) (xy 303.53 68.58)
		)
		(stroke
			(width 0)
			(type default)
		)
	)
	(wire
		(pts
			(xy 102.87 102.87) (xy 99.06 102.87)
		)
		(stroke
			(width 0)
			(type default)
		)
	)
	(wire
		(pts
			(xy 80.01 105.41) (xy 80.01 102.87)
		)
		(stroke
			(width 0)
			(type default)
		)
	)
	(wire
		(pts
			(xy 170.815 162.56) (xy 163.195 162.56)
		)
		(stroke
			(width 0)
			(type default)
		)
	)
	(wire
		(pts
			(xy 224.155 114.935) (xy 224.155 124.46)
		)
		(stroke
			(width 0)
			(type default)
		)
	)
	(wire
		(pts
			(xy 125.73 105.41) (xy 125.73 102.87)
		)
		(stroke
			(width 0)
			(type default)
		)
	)
	(wire
		(pts
			(xy 265.43 81.915) (xy 265.43 79.375)
		)
		(stroke
			(width 0)
			(type default)
		)
	)
	(wire
		(pts
			(xy 102.87 68.58) (xy 116.84 68.58)
		)
		(stroke
			(width 0)
			(type default)
		)
	)
	(wire
		(pts
			(xy 281.94 102.87) (xy 287.655 102.87)
		)
		(stroke
			(width 0)
			(type default)
		)
	)
	(wire
		(pts
			(xy 208.915 121.92) (xy 226.695 121.92)
		)
		(stroke
			(width 0)
			(type default)
		)
	)
	(wire
		(pts
			(xy 170.815 170.18) (xy 163.195 170.18)
		)
		(stroke
			(width 0)
			(type default)
		)
	)
	(wire
		(pts
			(xy 276.86 79.375) (xy 276.86 81.915)
		)
		(stroke
			(width 0)
			(type default)
		)
	)
	(wire
		(pts
			(xy 208.915 162.56) (xy 216.535 162.56)
		)
		(stroke
			(width 0)
			(type default)
		)
	)
	(wire
		(pts
			(xy 281.94 79.375) (xy 287.655 79.375)
		)
		(stroke
			(width 0)
			(type default)
		)
	)
	(wire
		(pts
			(xy 146.05 137.16) (xy 149.86 137.16)
		)
		(stroke
			(width 0)
			(type default)
		)
	)
	(wire
		(pts
			(xy 208.915 165.1) (xy 216.535 165.1)
		)
		(stroke
			(width 0)
			(type default)
		)
	)
	(wire
		(pts
			(xy 114.3 81.915) (xy 114.3 79.375)
		)
		(stroke
			(width 0)
			(type default)
		)
	)
	(wire
		(pts
			(xy 170.815 144.78) (xy 163.195 144.78)
		)
		(stroke
			(width 0)
			(type default)
		)
	)
	(wire
		(pts
			(xy 226.695 121.92) (xy 233.045 121.92)
		)
		(stroke
			(width 0)
			(type default)
		)
	)
	(wire
		(pts
			(xy 274.32 68.58) (xy 284.48 68.58)
		)
		(stroke
			(width 0)
			(type default)
		)
	)
	(wire
		(pts
			(xy 259.715 102.87) (xy 265.43 102.87)
		)
		(stroke
			(width 0)
			(type default)
		)
	)
	(wire
		(pts
			(xy 303.53 79.375) (xy 309.245 79.375)
		)
		(stroke
			(width 0)
			(type default)
		)
	)
	(wire
		(pts
			(xy 246.38 177.8) (xy 236.855 177.8)
		)
		(stroke
			(width 0)
			(type default)
		)
	)
	(wire
		(pts
			(xy 170.815 165.1) (xy 163.195 165.1)
		)
		(stroke
			(width 0)
			(type default)
		)
	)
	(wire
		(pts
			(xy 170.815 129.54) (xy 163.195 129.54)
		)
		(stroke
			(width 0)
			(type default)
		)
	)
	(wire
		(pts
			(xy 238.125 121.92) (xy 245.11 121.92)
		)
		(stroke
			(width 0)
			(type default)
		)
	)
	(wire
		(pts
			(xy 155.575 121.92) (xy 170.815 121.92)
		)
		(stroke
			(width 0)
			(type default)
		)
	)
	(wire
		(pts
			(xy 292.1 79.375) (xy 297.815 79.375)
		)
		(stroke
			(width 0)
			(type default)
		)
	)
	(wire
		(pts
			(xy 170.815 167.64) (xy 163.195 167.64)
		)
		(stroke
			(width 0)
			(type default)
		)
	)
	(wire
		(pts
			(xy 170.815 154.94) (xy 163.195 154.94)
		)
		(stroke
			(width 0)
			(type default)
		)
	)
	(wire
		(pts
			(xy 226.695 121.92) (xy 226.695 114.935)
		)
		(stroke
			(width 0)
			(type default)
		)
	)
	(wire
		(pts
			(xy 170.815 172.72) (xy 163.195 172.72)
		)
		(stroke
			(width 0)
			(type default)
		)
	)
	(wire
		(pts
			(xy 102.87 105.41) (xy 102.87 102.87)
		)
		(stroke
			(width 0)
			(type default)
		)
	)
	(wire
		(pts
			(xy 246.38 132.08) (xy 238.125 132.08)
		)
		(stroke
			(width 0)
			(type default)
		)
	)
	(wire
		(pts
			(xy 271.145 102.87) (xy 276.86 102.87)
		)
		(stroke
			(width 0)
			(type default)
		)
	)
	(wire
		(pts
			(xy 208.915 154.94) (xy 216.535 154.94)
		)
		(stroke
			(width 0)
			(type default)
		)
	)
	(polyline
		(pts
			(xy 119.38 283.845) (xy 118.745 283.845)
		)
		(stroke
			(width 0)
			(type dash)
		)
	)
	(wire
		(pts
			(xy 125.73 79.375) (xy 121.92 79.375)
		)
		(stroke
			(width 0)
			(type default)
		)
	)
	(label "R_ODT_CA_A"
		(at 211.455 124.46 0)
		(effects
			(font
				(size 1.27 1.27)
			)
			(justify left bottom)
		)
	)
	(label "VDDQ"
		(at 303.53 102.87 0)
		(effects
			(font
				(size 1.27 1.27)
			)
			(justify left bottom)
		)
	)
	(label "R_MIR"
		(at 211.455 132.08 0)
		(effects
			(font
				(size 1.27 1.27)
			)
			(justify left bottom)
		)
	)
	(label "VDD"
		(at 87.63 79.375 0)
		(effects
			(font
				(size 1.27 1.27)
			)
			(justify left bottom)
		)
	)
	(label "VPP"
		(at 155.575 124.46 0)
		(effects
			(font
				(size 1.27 1.27)
			)
			(justify left bottom)
		)
	)
	(label "VDD"
		(at 116.84 68.58 180)
		(effects
			(font
				(size 1.27 1.27)
			)
			(justify right bottom)
		)
	)
	(label "R_RESET_N"
		(at 211.455 121.92 0)
		(effects
			(font
				(size 1.27 1.27)
			)
			(justify left bottom)
		)
	)
	(label "R_LBDQS"
		(at 213.36 180.34 0)
		(effects
			(font
				(size 1.27 1.27)
			)
			(justify left bottom)
		)
	)
	(label "VDD"
		(at 76.2 79.375 0)
		(effects
			(font
				(size 1.27 1.27)
			)
			(justify left bottom)
		)
	)
	(label "VDDQ"
		(at 292.1 102.87 0)
		(effects
			(font
				(size 1.27 1.27)
			)
			(justify left bottom)
		)
	)
	(label "VDDQ"
		(at 271.145 102.87 0)
		(effects
			(font
				(size 1.27 1.27)
			)
			(justify left bottom)
		)
	)
	(label "VDDQ"
		(at 303.53 68.58 180)
		(effects
			(font
				(size 1.27 1.27)
			)
			(justify right bottom)
		)
	)
	(label "VDD"
		(at 121.92 79.375 0)
		(effects
			(font
				(size 1.27 1.27)
			)
			(justify left bottom)
		)
	)
	(label "VDDQ"
		(at 215.265 104.775 0)
		(effects
			(font
				(size 1.27 1.27)
			)
			(justify left bottom)
		)
	)
	(label "R_CAI"
		(at 211.455 129.54 0)
		(effects
			(font
				(size 1.27 1.27)
			)
			(justify left bottom)
		)
	)
	(label "VDD"
		(at 87.63 102.87 0)
		(effects
			(font
				(size 1.27 1.27)
			)
			(justify left bottom)
		)
	)
	(label "R_TEN"
		(at 211.455 134.62 0)
		(effects
			(font
				(size 1.27 1.27)
			)
			(justify left bottom)
		)
	)
	(label "VPP"
		(at 203.2 68.58 180)
		(effects
			(font
				(size 1.27 1.27)
			)
			(justify right bottom)
		)
	)
	(label "VPP"
		(at 190.5 79.375 0)
		(effects
			(font
				(size 1.27 1.27)
			)
			(justify left bottom)
		)
	)
	(label "VDDQ"
		(at 259.715 102.87 0)
		(effects
			(font
				(size 1.27 1.27)
			)
			(justify left bottom)
		)
	)
	(label "VDDQ"
		(at 281.94 79.375 0)
		(effects
			(font
				(size 1.27 1.27)
			)
			(justify left bottom)
		)
	)
	(label "VDD"
		(at 110.49 79.375 0)
		(effects
			(font
				(size 1.27 1.27)
			)
			(justify left bottom)
		)
	)
	(label "VDDQ"
		(at 292.1 79.375 0)
		(effects
			(font
				(size 1.27 1.27)
			)
			(justify left bottom)
		)
	)
	(label "VDDQ"
		(at 259.715 79.375 0)
		(effects
			(font
				(size 1.27 1.27)
			)
			(justify left bottom)
		)
	)
	(label "VDDQ"
		(at 271.145 79.375 0)
		(effects
			(font
				(size 1.27 1.27)
			)
			(justify left bottom)
		)
	)
	(label "R_LBDQ"
		(at 213.36 177.8 0)
		(effects
			(font
				(size 1.27 1.27)
			)
			(justify left bottom)
		)
	)
	(label "VDD"
		(at 121.92 102.87 0)
		(effects
			(font
				(size 1.27 1.27)
			)
			(justify left bottom)
		)
	)
	(label "VDD"
		(at 155.575 121.92 0)
		(effects
			(font
				(size 1.27 1.27)
			)
			(justify left bottom)
		)
	)
	(label "VDDQ"
		(at 303.53 79.375 0)
		(effects
			(font
				(size 1.27 1.27)
			)
			(justify left bottom)
		)
	)
	(label "VDDQ"
		(at 155.575 127 0)
		(effects
			(font
				(size 1.27 1.27)
			)
			(justify left bottom)
		)
	)
	(label "VDD"
		(at 76.2 102.87 0)
		(effects
			(font
				(size 1.27 1.27)
			)
			(justify left bottom)
		)
	)
	(label "ZQ"
		(at 163.83 182.88 0)
		(effects
			(font
				(size 1.27 1.27)
			)
			(justify left bottom)
		)
	)
	(label "R_ALERT_N"
		(at 211.455 127 0)
		(effects
			(font
				(size 1.27 1.27)
			)
			(justify left bottom)
		)
	)
	(label "VDD"
		(at 99.06 79.375 0)
		(effects
			(font
				(size 1.27 1.27)
			)
			(justify left bottom)
		)
	)
	(label "VDD"
		(at 99.06 102.87 0)
		(effects
			(font
				(size 1.27 1.27)
			)
			(justify left bottom)
		)
	)
	(label "VPP"
		(at 180.34 79.375 0)
		(effects
			(font
				(size 1.27 1.27)
			)
			(justify left bottom)
		)
	)
	(label "VDD"
		(at 110.49 102.87 0)
		(effects
			(font
				(size 1.27 1.27)
			)
			(justify left bottom)
		)
	)
	(label "VDDQ"
		(at 314.325 79.375 0)
		(effects
			(font
				(size 1.27 1.27)
			)
			(justify left bottom)
		)
	)
	(label "VDDQ"
		(at 281.94 102.87 0)
		(effects
			(font
				(size 1.27 1.27)
			)
			(justify left bottom)
		)
	)
	(global_label "1V1_SYS"
		(shape input)
		(at 274.32 68.58 180)
		(fields_autoplaced yes)
		(effects
			(font
				(size 1.27 1.27)
			)
			(justify right)
		)
		(property "Intersheetrefs" "${INTERSHEET_REFS}"
			(at 264.0129 68.5006 0)
			(effects
				(font
					(size 1.27 1.27)
				)
				(justify right)
				(hide yes)
			)
		)
	)
	(global_label "CA10"
		(shape bidirectional)
		(at 163.195 165.1 180)
		(fields_autoplaced yes)
		(effects
			(font
				(size 1.27 1.27)
			)
			(justify right)
		)
		(property "Intersheetrefs" "${INTERSHEET_REFS}"
			(at 156.0932 165.0206 0)
			(effects
				(font
					(size 1.27 1.27)
				)
				(justify right)
				(hide yes)
			)
		)
	)
	(global_label "DQ7"
		(shape bidirectional)
		(at 216.535 165.1 0)
		(fields_autoplaced yes)
		(effects
			(font
				(size 1.27 1.27)
			)
			(justify left)
		)
		(property "Intersheetrefs" "${INTERSHEET_REFS}"
			(at 222.6692 165.0206 0)
			(effects
				(font
					(size 1.27 1.27)
				)
				(justify left)
				(hide yes)
			)
		)
	)
	(global_label "CAI"
		(shape input)
		(at 246.38 129.54 0)
		(fields_autoplaced yes)
		(effects
			(font
				(size 1.27 1.27)
			)
			(justify left)
		)
		(property "Intersheetrefs" "${INTERSHEET_REFS}"
			(at 251.6675 129.4606 0)
			(effects
				(font
					(size 1.27 1.27)
				)
				(justify left)
				(hide yes)
			)
		)
	)
	(global_label "CA8"
		(shape bidirectional)
		(at 163.195 160.02 180)
		(fields_autoplaced yes)
		(effects
			(font
				(size 1.27 1.27)
			)
			(justify right)
		)
		(property "Intersheetrefs" "${INTERSHEET_REFS}"
			(at 157.3027 159.9406 0)
			(effects
				(font
					(size 1.27 1.27)
				)
				(justify right)
				(hide yes)
			)
		)
	)
	(global_label "CS_N"
		(shape input)
		(at 146.05 137.16 180)
		(fields_autoplaced yes)
		(effects
			(font
				(size 1.27 1.27)
			)
			(justify right)
		)
		(property "Intersheetrefs" "${INTERSHEET_REFS}"
			(at 138.9482 137.0806 0)
			(effects
				(font
					(size 1.27 1.27)
				)
				(justify right)
				(hide yes)
			)
		)
	)
	(global_label "DQ5"
		(shape bidirectional)
		(at 216.535 160.02 0)
		(fields_autoplaced yes)
		(effects
			(font
				(size 1.27 1.27)
			)
			(justify left)
		)
		(property "Intersheetrefs" "${INTERSHEET_REFS}"
			(at 222.6692 159.9406 0)
			(effects
				(font
					(size 1.27 1.27)
				)
				(justify left)
				(hide yes)
			)
		)
	)
	(global_label "TDQS_N"
		(shape output)
		(at 216.535 172.72 0)
		(fields_autoplaced yes)
		(effects
			(font
				(size 1.27 1.27)
			)
			(justify left)
		)
		(property "Intersheetrefs" "${INTERSHEET_REFS}"
			(at 225.9349 172.6406 0)
			(effects
				(font
					(size 1.27 1.27)
				)
				(justify left)
				(hide yes)
			)
		)
	)
	(global_label "1V8_SYS"
		(shape input)
		(at 173.99 68.58 180)
		(fields_autoplaced yes)
		(effects
			(font
				(size 1.27 1.27)
			)
			(justify right)
		)
		(property "Intersheetrefs" "${INTERSHEET_REFS}"
			(at 163.6829 68.5006 0)
			(effects
				(font
					(size 1.27 1.27)
				)
				(justify right)
				(hide yes)
			)
		)
	)
	(global_label "CA6"
		(shape bidirectional)
		(at 163.195 154.94 180)
		(fields_autoplaced yes)
		(effects
			(font
				(size 1.27 1.27)
			)
			(justify right)
		)
		(property "Intersheetrefs" "${INTERSHEET_REFS}"
			(at 157.3027 154.8606 0)
			(effects
				(font
					(size 1.27 1.27)
				)
				(justify right)
				(hide yes)
			)
		)
	)
	(global_label "CA12"
		(shape bidirectional)
		(at 163.195 170.18 180)
		(fields_autoplaced yes)
		(effects
			(font
				(size 1.27 1.27)
			)
			(justify right)
		)
		(property "Intersheetrefs" "${INTERSHEET_REFS}"
			(at 156.0932 170.1006 0)
			(effects
				(font
					(size 1.27 1.27)
				)
				(justify right)
				(hide yes)
			)
		)
	)
	(global_label "DQ1"
		(shape bidirectional)
		(at 216.535 149.86 0)
		(fields_autoplaced yes)
		(effects
			(font
				(size 1.27 1.27)
			)
			(justify left)
		)
		(property "Intersheetrefs" "${INTERSHEET_REFS}"
			(at 222.6692 149.7806 0)
			(effects
				(font
					(size 1.27 1.27)
				)
				(justify left)
				(hide yes)
			)
		)
	)
	(global_label "LBDQS"
		(shape output)
		(at 246.38 180.34 0)
		(fields_autoplaced yes)
		(effects
			(font
				(size 1.27 1.27)
			)
			(justify left)
		)
		(property "Intersheetrefs" "${INTERSHEET_REFS}"
			(at 254.8123 180.2606 0)
			(effects
				(font
					(size 1.27 1.27)
				)
				(justify left)
				(hide yes)
			)
		)
	)
	(global_label "CA5"
		(shape bidirectional)
		(at 163.195 152.4 180)
		(fields_autoplaced yes)
		(effects
			(font
				(size 1.27 1.27)
			)
			(justify right)
		)
		(property "Intersheetrefs" "${INTERSHEET_REFS}"
			(at 157.3027 152.3206 0)
			(effects
				(font
					(size 1.27 1.27)
				)
				(justify right)
				(hide yes)
			)
		)
	)
	(global_label "DQ4"
		(shape bidirectional)
		(at 216.535 157.48 0)
		(fields_autoplaced yes)
		(effects
			(font
				(size 1.27 1.27)
			)
			(justify left)
		)
		(property "Intersheetrefs" "${INTERSHEET_REFS}"
			(at 222.6692 157.4006 0)
			(effects
				(font
					(size 1.27 1.27)
				)
				(justify left)
				(hide yes)
			)
		)
	)
	(global_label "TDQS_P"
		(shape output)
		(at 216.535 170.18 0)
		(fields_autoplaced yes)
		(effects
			(font
				(size 1.27 1.27)
			)
			(justify left)
		)
		(property "Intersheetrefs" "${INTERSHEET_REFS}"
			(at 225.8744 170.1006 0)
			(effects
				(font
					(size 1.27 1.27)
				)
				(justify left)
				(hide yes)
			)
		)
	)
	(global_label "DQS_P"
		(shape bidirectional)
		(at 163.195 177.8 180)
		(fields_autoplaced yes)
		(effects
			(font
				(size 1.27 1.27)
			)
			(justify right)
		)
		(property "Intersheetrefs" "${INTERSHEET_REFS}"
			(at 154.8232 177.7206 0)
			(effects
				(font
					(size 1.27 1.27)
				)
				(justify right)
				(hide yes)
			)
		)
	)
	(global_label "OTD_CA_A"
		(shape input)
		(at 245.11 124.46 0)
		(fields_autoplaced yes)
		(effects
			(font
				(size 1.27 1.27)
			)
			(justify left)
		)
		(property "Intersheetrefs" "${INTERSHEET_REFS}"
			(at 256.3847 124.3806 0)
			(effects
				(font
					(size 1.27 1.27)
				)
				(justify left)
				(hide yes)
			)
		)
	)
	(global_label "CA7"
		(shape bidirectional)
		(at 163.195 157.48 180)
		(fields_autoplaced yes)
		(effects
			(font
				(size 1.27 1.27)
			)
			(justify right)
		)
		(property "Intersheetrefs" "${INTERSHEET_REFS}"
			(at 157.3027 157.4006 0)
			(effects
				(font
					(size 1.27 1.27)
				)
				(justify right)
				(hide yes)
			)
		)
	)
	(global_label "ALERT_N"
		(shape bidirectional)
		(at 246.38 127 0)
		(fields_autoplaced yes)
		(effects
			(font
				(size 1.27 1.27)
			)
			(justify left)
		)
		(property "Intersheetrefs" "${INTERSHEET_REFS}"
			(at 256.5056 126.9206 0)
			(effects
				(font
					(size 1.27 1.27)
				)
				(justify left)
				(hide yes)
			)
		)
	)
	(global_label "CA1"
		(shape bidirectional)
		(at 163.195 142.24 180)
		(fields_autoplaced yes)
		(effects
			(font
				(size 1.27 1.27)
			)
			(justify right)
		)
		(property "Intersheetrefs" "${INTERSHEET_REFS}"
			(at 157.3027 142.1606 0)
			(effects
				(font
					(size 1.27 1.27)
				)
				(justify right)
				(hide yes)
			)
		)
	)
	(global_label "CLK_P"
		(shape input)
		(at 163.195 129.54 180)
		(fields_autoplaced yes)
		(effects
			(font
				(size 1.27 1.27)
			)
			(justify right)
		)
		(property "Intersheetrefs" "${INTERSHEET_REFS}"
			(at 155.0651 129.4606 0)
			(effects
				(font
					(size 1.27 1.27)
				)
				(justify right)
				(hide yes)
			)
		)
	)
	(global_label "CA11"
		(shape bidirectional)
		(at 163.195 167.64 180)
		(fields_autoplaced yes)
		(effects
			(font
				(size 1.27 1.27)
			)
			(justify right)
		)
		(property "Intersheetrefs" "${INTERSHEET_REFS}"
			(at 156.0932 167.5606 0)
			(effects
				(font
					(size 1.27 1.27)
				)
				(justify right)
				(hide yes)
			)
		)
	)
	(global_label "CA2"
		(shape bidirectional)
		(at 163.195 144.78 180)
		(fields_autoplaced yes)
		(effects
			(font
				(size 1.27 1.27)
			)
			(justify right)
		)
		(property "Intersheetrefs" "${INTERSHEET_REFS}"
			(at 157.3027 144.7006 0)
			(effects
				(font
					(size 1.27 1.27)
				)
				(justify right)
				(hide yes)
			)
		)
	)
	(global_label "LBDQ"
		(shape output)
		(at 246.38 177.8 0)
		(fields_autoplaced yes)
		(effects
			(font
				(size 1.27 1.27)
			)
			(justify left)
		)
		(property "Intersheetrefs" "${INTERSHEET_REFS}"
			(at 253.6028 177.7206 0)
			(effects
				(font
					(size 1.27 1.27)
				)
				(justify left)
				(hide yes)
			)
		)
	)
	(global_label "DQ2"
		(shape bidirectional)
		(at 216.535 152.4 0)
		(fields_autoplaced yes)
		(effects
			(font
				(size 1.27 1.27)
			)
			(justify left)
		)
		(property "Intersheetrefs" "${INTERSHEET_REFS}"
			(at 222.6692 152.3206 0)
			(effects
				(font
					(size 1.27 1.27)
				)
				(justify left)
				(hide yes)
			)
		)
	)
	(global_label "TEN"
		(shape input)
		(at 246.38 134.62 0)
		(fields_autoplaced yes)
		(effects
			(font
				(size 1.27 1.27)
			)
			(justify left)
		)
		(property "Intersheetrefs" "${INTERSHEET_REFS}"
			(at 252.1513 134.5406 0)
			(effects
				(font
					(size 1.27 1.27)
				)
				(justify left)
				(hide yes)
			)
		)
	)
	(global_label "CA0"
		(shape bidirectional)
		(at 163.195 139.7 180)
		(fields_autoplaced yes)
		(effects
			(font
				(size 1.27 1.27)
			)
			(justify right)
		)
		(property "Intersheetrefs" "${INTERSHEET_REFS}"
			(at 157.3027 139.6206 0)
			(effects
				(font
					(size 1.27 1.27)
				)
				(justify right)
				(hide yes)
			)
		)
	)
	(global_label "DQ3"
		(shape bidirectional)
		(at 216.535 154.94 0)
		(fields_autoplaced yes)
		(effects
			(font
				(size 1.27 1.27)
			)
			(justify left)
		)
		(property "Intersheetrefs" "${INTERSHEET_REFS}"
			(at 222.6692 154.8606 0)
			(effects
				(font
					(size 1.27 1.27)
				)
				(justify left)
				(hide yes)
			)
		)
	)
	(global_label "RESET_N"
		(shape input)
		(at 245.11 121.92 0)
		(fields_autoplaced yes)
		(effects
			(font
				(size 1.27 1.27)
			)
			(justify left)
		)
		(property "Intersheetrefs" "${INTERSHEET_REFS}"
			(at 255.4775 121.8406 0)
			(effects
				(font
					(size 1.27 1.27)
				)
				(justify left)
				(hide yes)
			)
		)
	)
	(global_label "CLK_N"
		(shape input)
		(at 163.195 132.08 180)
		(fields_autoplaced yes)
		(effects
			(font
				(size 1.27 1.27)
			)
			(justify right)
		)
		(property "Intersheetrefs" "${INTERSHEET_REFS}"
			(at 155.0046 132.0006 0)
			(effects
				(font
					(size 1.27 1.27)
				)
				(justify right)
				(hide yes)
			)
		)
	)
	(global_label "CA13"
		(shape bidirectional)
		(at 163.195 172.72 180)
		(fields_autoplaced yes)
		(effects
			(font
				(size 1.27 1.27)
			)
			(justify right)
		)
		(property "Intersheetrefs" "${INTERSHEET_REFS}"
			(at 156.0932 172.6406 0)
			(effects
				(font
					(size 1.27 1.27)
				)
				(justify right)
				(hide yes)
			)
		)
	)
	(global_label "CA4"
		(shape bidirectional)
		(at 163.195 149.86 180)
		(fields_autoplaced yes)
		(effects
			(font
				(size 1.27 1.27)
			)
			(justify right)
		)
		(property "Intersheetrefs" "${INTERSHEET_REFS}"
			(at 157.3027 149.7806 0)
			(effects
				(font
					(size 1.27 1.27)
				)
				(justify right)
				(hide yes)
			)
		)
	)
	(global_label "DQS_N"
		(shape bidirectional)
		(at 163.195 180.34 180)
		(fields_autoplaced yes)
		(effects
			(font
				(size 1.27 1.27)
			)
			(justify right)
		)
		(property "Intersheetrefs" "${INTERSHEET_REFS}"
			(at 154.7627 180.2606 0)
			(effects
				(font
					(size 1.27 1.27)
				)
				(justify right)
				(hide yes)
			)
		)
	)
	(global_label "CA3"
		(shape bidirectional)
		(at 163.195 147.32 180)
		(fields_autoplaced yes)
		(effects
			(font
				(size 1.27 1.27)
			)
			(justify right)
		)
		(property "Intersheetrefs" "${INTERSHEET_REFS}"
			(at 157.3027 147.2406 0)
			(effects
				(font
					(size 1.27 1.27)
				)
				(justify right)
				(hide yes)
			)
		)
	)
	(global_label "CA9"
		(shape bidirectional)
		(at 163.195 162.56 180)
		(fields_autoplaced yes)
		(effects
			(font
				(size 1.27 1.27)
			)
			(justify right)
		)
		(property "Intersheetrefs" "${INTERSHEET_REFS}"
			(at 157.3027 162.4806 0)
			(effects
				(font
					(size 1.27 1.27)
				)
				(justify right)
				(hide yes)
			)
		)
	)
	(global_label "MIR"
		(shape input)
		(at 246.38 132.08 0)
		(fields_autoplaced yes)
		(effects
			(font
				(size 1.27 1.27)
			)
			(justify left)
		)
		(property "Intersheetrefs" "${INTERSHEET_REFS}"
			(at 252.0304 132.0006 0)
			(effects
				(font
					(size 1.27 1.27)
				)
				(justify left)
				(hide yes)
			)
		)
	)
	(global_label "DQ6"
		(shape bidirectional)
		(at 216.535 162.56 0)
		(fields_autoplaced yes)
		(effects
			(font
				(size 1.27 1.27)
			)
			(justify left)
		)
		(property "Intersheetrefs" "${INTERSHEET_REFS}"
			(at 222.6692 162.4806 0)
			(effects
				(font
					(size 1.27 1.27)
				)
				(justify left)
				(hide yes)
			)
		)
	)
	(global_label "1V1_SYS"
		(shape input)
		(at 87.63 68.58 180)
		(fields_autoplaced yes)
		(effects
			(font
				(size 1.27 1.27)
			)
			(justify right)
		)
		(property "Intersheetrefs" "${INTERSHEET_REFS}"
			(at 77.3229 68.5006 0)
			(effects
				(font
					(size 1.27 1.27)
				)
				(justify right)
				(hide yes)
			)
		)
	)
	(global_label "DQ0"
		(shape bidirectional)
		(at 216.535 147.32 0)
		(fields_autoplaced yes)
		(effects
			(font
				(size 1.27 1.27)
			)
			(justify left)
		)
		(property "Intersheetrefs" "${INTERSHEET_REFS}"
			(at 222.6692 147.2406 0)
			(effects
				(font
					(size 1.27 1.27)
				)
				(justify left)
				(hide yes)
			)
		)
	)
	(symbol
		(lib_id "antmicroResistors0402:R_10k_0402")
		(at 149.86 142.24 270)
		(unit 1)
		(exclude_from_sim no)
		(in_bom yes)
		(on_board yes)
		(dnp no)
		(fields_autoplaced yes)
		(property "Reference" "R3"
			(at 152.4 143.51 90)
			(effects
				(font
					(size 1.27 1.27)
				)
				(justify left)
			)
		)
		(property "Value" "R_10k_0402"
			(at 137.16 162.56 0)
			(effects
				(font
					(size 1.27 1.27)
					(thickness 0.15)
				)
				(justify left bottom)
				(hide yes)
			)
		)
		(property "Footprint" "antmicro-footprints:R_0402_1005Metric"
			(at 134.62 162.56 0)
			(effects
				(font
					(size 1.27 1.27)
					(thickness 0.15)
				)
				(justify left bottom)
				(hide yes)
			)
		)
		(property "Datasheet" "https://www.bourns.com/docs/product-datasheets/cr.pdf"
			(at 132.08 162.56 0)
			(effects
				(font
					(size 1.27 1.27)
					(thickness 0.15)
				)
				(justify left bottom)
				(hide yes)
			)
		)
		(property "Description" ""
			(at 149.86 142.24 0)
			(effects
				(font
					(size 1.27 1.27)
				)
			)
		)
		(property "Manufacturer" "Bourns"
			(at 127 162.56 0)
			(effects
				(font
					(size 1.27 1.27)
					(thickness 0.15)
				)
				(justify left bottom)
				(hide yes)
			)
		)
		(property "MPN" "CR0402-FX-1002GLF"
			(at 129.54 162.56 0)
			(effects
				(font
					(size 1.27 1.27)
					(thickness 0.15)
				)
				(justify left bottom)
				(hide yes)
			)
		)
		(property "Val" "10k"
			(at 152.4 146.6849 90)
			(effects
				(font
					(size 1.27 1.27)
					(thickness 0.15)
				)
				(justify left)
			)
		)
		(property "License" "Apache-2.0"
			(at 124.46 162.56 0)
			(effects
				(font
					(size 1.27 1.27)
					(thickness 0.15)
				)
				(justify left bottom)
				(hide yes)
			)
		)
		(property "Author" "Antmicro"
			(at 121.92 162.56 0)
			(effects
				(font
					(size 1.27 1.27)
					(thickness 0.15)
				)
				(justify left bottom)
				(hide yes)
			)
		)
		(property "Tolerance" "1%"
			(at 139.7 162.56 0)
			(effects
				(font
					(size 1.27 1.27)
				)
				(justify left bottom)
				(hide yes)
			)
		)
		(pin "1"
		)
		(pin "2"
		)
		(instances
			(project "ddr5-testbed"
				(path ""
					(reference "R3")
					(unit 1)
				)
			)
		)
	)
	(symbol
		(lib_id "antmicropower:GND")
		(at 149.86 147.32 0)
		(unit 1)
		(exclude_from_sim no)
		(in_bom yes)
		(on_board yes)
		(dnp no)
		(fields_autoplaced yes)
		(property "Reference" "#PWR038"
			(at 149.86 153.67 0)
			(effects
				(font
					(size 1.27 1.27)
				)
				(hide yes)
			)
		)
		(property "Value" "GND"
			(at 149.86 152.4 0)
			(effects
				(font
					(size 1.27 1.27)
				)
			)
		)
		(property "Footprint" ""
			(at 149.86 147.32 0)
			(effects
				(font
					(size 1.27 1.27)
				)
				(hide yes)
			)
		)
		(property "Datasheet" ""
			(at 149.86 147.32 0)
			(effects
				(font
					(size 1.27 1.27)
				)
				(hide yes)
			)
		)
		(property "Description" ""
			(at 149.86 147.32 0)
			(effects
				(font
					(size 1.27 1.27)
				)
			)
		)
		(pin "1"
		)
		(instances
			(project "ddr5-testbed"
				(path ""
					(reference "#PWR038")
					(unit 1)
				)
			)
		)
	)
	(symbol
		(lib_id "antmicroCapacitorsmisc:C_100n_0201")
		(at 265.43 81.915 270)
		(unit 1)
		(exclude_from_sim no)
		(in_bom yes)
		(on_board yes)
		(dnp no)
		(fields_autoplaced yes)
		(property "Reference" "C1"
			(at 267.97 83.1913 90)
			(effects
				(font
					(size 1.27 1.27)
				)
				(justify left)
			)
		)
		(property "Value" "C_100n_0201"
			(at 255.27 102.235 0)
			(effects
				(font
					(size 1.27 1.27)
					(thickness 0.15)
				)
				(justify left bottom)
				(hide yes)
			)
		)
		(property "Footprint" "antmicro-footprints:C_0201"
			(at 252.73 102.235 0)
			(effects
				(font
					(size 1.27 1.27)
					(thickness 0.15)
				)
				(justify left bottom)
				(hide yes)
			)
		)
		(property "Datasheet" "https://www.yageo.com/en/Chart/Download/pdf/CC0201KRX6S5BB104"
			(at 250.19 102.235 0)
			(effects
				(font
					(size 1.27 1.27)
					(thickness 0.15)
				)
				(justify left bottom)
				(hide yes)
			)
		)
		(property "Description" ""
			(at 265.43 81.915 0)
			(effects
				(font
					(size 1.27 1.27)
				)
			)
		)
		(property "Manufacturer" "YAGEO"
			(at 245.11 102.235 0)
			(effects
				(font
					(size 1.27 1.27)
					(thickness 0.15)
				)
				(justify left bottom)
				(hide yes)
			)
		)
		(property "MPN" "CC0201KRX6S5BB104"
			(at 247.65 102.235 0)
			(effects
				(font
					(size 1.27 1.27)
					(thickness 0.15)
				)
				(justify left bottom)
				(hide yes)
			)
		)
		(property "Val" "100n"
			(at 267.97 86.3662 90)
			(effects
				(font
					(size 1.27 1.27)
					(thickness 0.15)
				)
				(justify left)
			)
		)
		(property "License" "Apache-2.0"
			(at 242.57 102.235 0)
			(effects
				(font
					(size 1.27 1.27)
					(thickness 0.15)
				)
				(justify left bottom)
				(hide yes)
			)
		)
		(property "Author" "Antmicro"
			(at 240.03 102.235 0)
			(effects
				(font
					(size 1.27 1.27)
					(thickness 0.15)
				)
				(justify left bottom)
				(hide yes)
			)
		)
		(property "Voltage" ""
			(at 237.49 102.235 0)
			(effects
				(font
					(size 1.27 1.27)
				)
				(justify left bottom)
				(hide yes)
			)
		)
		(property "Dielectric" ""
			(at 234.95 102.235 0)
			(effects
				(font
					(size 1.27 1.27)
				)
				(justify left bottom)
				(hide yes)
			)
		)
		(property "Public" "False"
			(at 232.41 102.235 0)
			(effects
				(font
					(size 1.27 1.27)
				)
				(justify left bottom)
				(hide yes)
			)
		)
		(pin "1"
		)
		(pin "2"
		)
		(instances
			(project "ddr5-testbed"
				(path ""
					(reference "C1")
					(unit 1)
				)
			)
		)
	)
	(symbol
		(lib_id "antmicroResistors0402:R_0R_0402")
		(at 233.045 124.46 0)
		(unit 1)
		(exclude_from_sim no)
		(in_bom yes)
		(on_board yes)
		(dnp no)
		(property "Reference" "R2"
			(at 229.87 123.19 0)
			(effects
				(font
					(size 1.27 1.27)
				)
			)
		)
		(property "Value" "R_0R_0402"
			(at 253.365 137.16 0)
			(effects
				(font
					(size 1.27 1.27)
					(thickness 0.15)
				)
				(justify left bottom)
				(hide yes)
			)
		)
		(property "Footprint" "antmicro-footprints:R_0402_1005Metric"
			(at 253.365 139.7 0)
			(effects
				(font
					(size 1.27 1.27)
					(thickness 0.15)
				)
				(justify left bottom)
				(hide yes)
			)
		)
		(property "Datasheet" "https://industrial.panasonic.com/cdbs/www-data/pdf/RDA0000/AOA0000C301.pdf"
			(at 253.365 142.24 0)
			(effects
				(font
					(size 1.27 1.27)
					(thickness 0.15)
				)
				(justify left bottom)
				(hide yes)
			)
		)
		(property "Description" ""
			(at 233.045 124.46 0)
			(effects
				(font
					(size 1.27 1.27)
				)
			)
		)
		(property "Manufacturer" "Panasonic"
			(at 253.365 147.32 0)
			(effects
				(font
					(size 1.27 1.27)
					(thickness 0.15)
				)
				(justify left bottom)
				(hide yes)
			)
		)
		(property "MPN" "ERJ2GE0R00X"
			(at 253.365 144.78 0)
			(effects
				(font
					(size 1.27 1.27)
					(thickness 0.15)
				)
				(justify left bottom)
				(hide yes)
			)
		)
		(property "Val" "0R"
			(at 239.395 123.19 0)
			(effects
				(font
					(size 1.27 1.27)
					(thickness 0.15)
				)
			)
		)
		(property "License" "Apache-2.0"
			(at 253.365 149.86 0)
			(effects
				(font
					(size 1.27 1.27)
					(thickness 0.15)
				)
				(justify left bottom)
				(hide yes)
			)
		)
		(property "Author" "Antmicro"
			(at 253.365 152.4 0)
			(effects
				(font
					(size 1.27 1.27)
					(thickness 0.15)
				)
				(justify left bottom)
				(hide yes)
			)
		)
		(property "Tolerance" "~"
			(at 253.365 134.62 0)
			(effects
				(font
					(size 1.27 1.27)
				)
				(justify left bottom)
				(hide yes)
			)
		)
		(property "Current" "1A"
			(at 253.365 154.94 0)
			(effects
				(font
					(size 1.27 1.27)
					(thickness 0.15)
				)
				(justify left bottom)
				(hide yes)
			)
		)
		(pin "1"
		)
		(pin "2"
		)
		(instances
			(project "ddr5-testbed"
				(path ""
					(reference "R2")
					(unit 1)
				)
			)
		)
	)
	(symbol
		(lib_id "antmicropower:GND")
		(at 265.43 86.995 0)
		(unit 1)
		(exclude_from_sim no)
		(in_bom yes)
		(on_board yes)
		(dnp no)
		(fields_autoplaced yes)
		(property "Reference" "#PWR01"
			(at 265.43 93.345 0)
			(effects
				(font
					(size 1.27 1.27)
				)
				(hide yes)
			)
		)
		(property "Value" "GND"
			(at 265.43 91.44 0)
			(effects
				(font
					(size 1.27 1.27)
				)
			)
		)
		(property "Footprint" ""
			(at 265.43 86.995 0)
			(effects
				(font
					(size 1.27 1.27)
				)
				(hide yes)
			)
		)
		(property "Datasheet" ""
			(at 265.43 86.995 0)
			(effects
				(font
					(size 1.27 1.27)
				)
				(hide yes)
			)
		)
		(property "Description" ""
			(at 265.43 86.995 0)
			(effects
				(font
					(size 1.27 1.27)
				)
			)
		)
		(pin "1"
		)
		(instances
			(project "ddr5-testbed"
				(path ""
					(reference "#PWR01")
					(unit 1)
				)
			)
		)
	)
	(symbol
		(lib_id "antmicroCapacitorsmisc:C_100n_0201")
		(at 276.86 81.915 270)
		(unit 1)
		(exclude_from_sim no)
		(in_bom yes)
		(on_board yes)
		(dnp no)
		(fields_autoplaced yes)
		(property "Reference" "C4"
			(at 279.4 83.1913 90)
			(effects
				(font
					(size 1.27 1.27)
				)
				(justify left)
			)
		)
		(property "Value" "C_100n_0201"
			(at 266.7 102.235 0)
			(effects
				(font
					(size 1.27 1.27)
					(thickness 0.15)
				)
				(justify left bottom)
				(hide yes)
			)
		)
		(property "Footprint" "antmicro-footprints:C_0201"
			(at 264.16 102.235 0)
			(effects
				(font
					(size 1.27 1.27)
					(thickness 0.15)
				)
				(justify left bottom)
				(hide yes)
			)
		)
		(property "Datasheet" "https://www.yageo.com/en/Chart/Download/pdf/CC0201KRX6S5BB104"
			(at 261.62 102.235 0)
			(effects
				(font
					(size 1.27 1.27)
					(thickness 0.15)
				)
				(justify left bottom)
				(hide yes)
			)
		)
		(property "Description" ""
			(at 276.86 81.915 0)
			(effects
				(font
					(size 1.27 1.27)
				)
			)
		)
		(property "Manufacturer" "YAGEO"
			(at 256.54 102.235 0)
			(effects
				(font
					(size 1.27 1.27)
					(thickness 0.15)
				)
				(justify left bottom)
				(hide yes)
			)
		)
		(property "MPN" "CC0201KRX6S5BB104"
			(at 259.08 102.235 0)
			(effects
				(font
					(size 1.27 1.27)
					(thickness 0.15)
				)
				(justify left bottom)
				(hide yes)
			)
		)
		(property "Val" "100n"
			(at 279.4 86.3662 90)
			(effects
				(font
					(size 1.27 1.27)
					(thickness 0.15)
				)
				(justify left)
			)
		)
		(property "License" "Apache-2.0"
			(at 254 102.235 0)
			(effects
				(font
					(size 1.27 1.27)
					(thickness 0.15)
				)
				(justify left bottom)
				(hide yes)
			)
		)
		(property "Author" "Antmicro"
			(at 251.46 102.235 0)
			(effects
				(font
					(size 1.27 1.27)
					(thickness 0.15)
				)
				(justify left bottom)
				(hide yes)
			)
		)
		(property "Voltage" ""
			(at 248.92 102.235 0)
			(effects
				(font
					(size 1.27 1.27)
				)
				(justify left bottom)
				(hide yes)
			)
		)
		(property "Dielectric" ""
			(at 246.38 102.235 0)
			(effects
				(font
					(size 1.27 1.27)
				)
				(justify left bottom)
				(hide yes)
			)
		)
		(property "Public" "False"
			(at 243.84 102.235 0)
			(effects
				(font
					(size 1.27 1.27)
				)
				(justify left bottom)
				(hide yes)
			)
		)
		(pin "1"
		)
		(pin "2"
		)
		(instances
			(project "ddr5-testbed"
				(path ""
					(reference "C4")
					(unit 1)
				)
			)
		)
	)
	(symbol
		(lib_id "antmicroCapacitorsmisc:C_100n_0201")
		(at 287.655 81.915 270)
		(unit 1)
		(exclude_from_sim no)
		(in_bom yes)
		(on_board yes)
		(dnp no)
		(fields_autoplaced yes)
		(property "Reference" "C7"
			(at 290.83 83.1913 90)
			(effects
				(font
					(size 1.27 1.27)
				)
				(justify left)
			)
		)
		(property "Value" "C_100n_0201"
			(at 277.495 102.235 0)
			(effects
				(font
					(size 1.27 1.27)
					(thickness 0.15)
				)
				(justify left bottom)
				(hide yes)
			)
		)
		(property "Footprint" "antmicro-footprints:C_0201"
			(at 274.955 102.235 0)
			(effects
				(font
					(size 1.27 1.27)
					(thickness 0.15)
				)
				(justify left bottom)
				(hide yes)
			)
		)
		(property "Datasheet" "https://www.yageo.com/en/Chart/Download/pdf/CC0201KRX6S5BB104"
			(at 272.415 102.235 0)
			(effects
				(font
					(size 1.27 1.27)
					(thickness 0.15)
				)
				(justify left bottom)
				(hide yes)
			)
		)
		(property "Description" ""
			(at 287.655 81.915 0)
			(effects
				(font
					(size 1.27 1.27)
				)
			)
		)
		(property "Manufacturer" "YAGEO"
			(at 267.335 102.235 0)
			(effects
				(font
					(size 1.27 1.27)
					(thickness 0.15)
				)
				(justify left bottom)
				(hide yes)
			)
		)
		(property "MPN" "CC0201KRX6S5BB104"
			(at 269.875 102.235 0)
			(effects
				(font
					(size 1.27 1.27)
					(thickness 0.15)
				)
				(justify left bottom)
				(hide yes)
			)
		)
		(property "Val" "100n"
			(at 290.83 86.3662 90)
			(effects
				(font
					(size 1.27 1.27)
					(thickness 0.15)
				)
				(justify left)
			)
		)
		(property "License" "Apache-2.0"
			(at 264.795 102.235 0)
			(effects
				(font
					(size 1.27 1.27)
					(thickness 0.15)
				)
				(justify left bottom)
				(hide yes)
			)
		)
		(property "Author" "Antmicro"
			(at 262.255 102.235 0)
			(effects
				(font
					(size 1.27 1.27)
					(thickness 0.15)
				)
				(justify left bottom)
				(hide yes)
			)
		)
		(property "Voltage" ""
			(at 259.715 102.235 0)
			(effects
				(font
					(size 1.27 1.27)
				)
				(justify left bottom)
				(hide yes)
			)
		)
		(property "Dielectric" ""
			(at 257.175 102.235 0)
			(effects
				(font
					(size 1.27 1.27)
				)
				(justify left bottom)
				(hide yes)
			)
		)
		(property "Public" "False"
			(at 254.635 102.235 0)
			(effects
				(font
					(size 1.27 1.27)
				)
				(justify left bottom)
				(hide yes)
			)
		)
		(pin "1"
		)
		(pin "2"
		)
		(instances
			(project "ddr5-testbed"
				(path ""
					(reference "C7")
					(unit 1)
				)
			)
		)
	)
	(symbol
		(lib_id "antmicroCapacitorsmisc:C_100n_0201")
		(at 297.815 81.915 270)
		(unit 1)
		(exclude_from_sim no)
		(in_bom yes)
		(on_board yes)
		(dnp no)
		(fields_autoplaced yes)
		(property "Reference" "C10"
			(at 300.99 83.1913 90)
			(effects
				(font
					(size 1.27 1.27)
				)
				(justify left)
			)
		)
		(property "Value" "C_100n_0201"
			(at 287.655 102.235 0)
			(effects
				(font
					(size 1.27 1.27)
					(thickness 0.15)
				)
				(justify left bottom)
				(hide yes)
			)
		)
		(property "Footprint" "antmicro-footprints:C_0201"
			(at 285.115 102.235 0)
			(effects
				(font
					(size 1.27 1.27)
					(thickness 0.15)
				)
				(justify left bottom)
				(hide yes)
			)
		)
		(property "Datasheet" "https://www.yageo.com/en/Chart/Download/pdf/CC0201KRX6S5BB104"
			(at 282.575 102.235 0)
			(effects
				(font
					(size 1.27 1.27)
					(thickness 0.15)
				)
				(justify left bottom)
				(hide yes)
			)
		)
		(property "Description" ""
			(at 297.815 81.915 0)
			(effects
				(font
					(size 1.27 1.27)
				)
			)
		)
		(property "Manufacturer" "YAGEO"
			(at 277.495 102.235 0)
			(effects
				(font
					(size 1.27 1.27)
					(thickness 0.15)
				)
				(justify left bottom)
				(hide yes)
			)
		)
		(property "MPN" "CC0201KRX6S5BB104"
			(at 280.035 102.235 0)
			(effects
				(font
					(size 1.27 1.27)
					(thickness 0.15)
				)
				(justify left bottom)
				(hide yes)
			)
		)
		(property "Val" "100n"
			(at 300.99 86.3662 90)
			(effects
				(font
					(size 1.27 1.27)
					(thickness 0.15)
				)
				(justify left)
			)
		)
		(property "License" "Apache-2.0"
			(at 274.955 102.235 0)
			(effects
				(font
					(size 1.27 1.27)
					(thickness 0.15)
				)
				(justify left bottom)
				(hide yes)
			)
		)
		(property "Author" "Antmicro"
			(at 272.415 102.235 0)
			(effects
				(font
					(size 1.27 1.27)
					(thickness 0.15)
				)
				(justify left bottom)
				(hide yes)
			)
		)
		(property "Voltage" ""
			(at 269.875 102.235 0)
			(effects
				(font
					(size 1.27 1.27)
				)
				(justify left bottom)
				(hide yes)
			)
		)
		(property "Dielectric" ""
			(at 267.335 102.235 0)
			(effects
				(font
					(size 1.27 1.27)
				)
				(justify left bottom)
				(hide yes)
			)
		)
		(property "Public" "False"
			(at 264.795 102.235 0)
			(effects
				(font
					(size 1.27 1.27)
				)
				(justify left bottom)
				(hide yes)
			)
		)
		(pin "1"
		)
		(pin "2"
		)
		(instances
			(project "ddr5-testbed"
				(path ""
					(reference "C10")
					(unit 1)
				)
			)
		)
	)
	(symbol
		(lib_id "antmicropower:GND")
		(at 276.86 86.995 0)
		(unit 1)
		(exclude_from_sim no)
		(in_bom yes)
		(on_board yes)
		(dnp no)
		(fields_autoplaced yes)
		(property "Reference" "#PWR04"
			(at 276.86 93.345 0)
			(effects
				(font
					(size 1.27 1.27)
				)
				(hide yes)
			)
		)
		(property "Value" "GND"
			(at 276.86 91.44 0)
			(effects
				(font
					(size 1.27 1.27)
				)
			)
		)
		(property "Footprint" ""
			(at 276.86 86.995 0)
			(effects
				(font
					(size 1.27 1.27)
				)
				(hide yes)
			)
		)
		(property "Datasheet" ""
			(at 276.86 86.995 0)
			(effects
				(font
					(size 1.27 1.27)
				)
				(hide yes)
			)
		)
		(property "Description" ""
			(at 276.86 86.995 0)
			(effects
				(font
					(size 1.27 1.27)
				)
			)
		)
		(pin "1"
		)
		(instances
			(project "ddr5-testbed"
				(path ""
					(reference "#PWR04")
					(unit 1)
				)
			)
		)
	)
	(symbol
		(lib_id "antmicropower:GND")
		(at 287.655 86.995 0)
		(unit 1)
		(exclude_from_sim no)
		(in_bom yes)
		(on_board yes)
		(dnp no)
		(fields_autoplaced yes)
		(property "Reference" "#PWR07"
			(at 287.655 93.345 0)
			(effects
				(font
					(size 1.27 1.27)
				)
				(hide yes)
			)
		)
		(property "Value" "GND"
			(at 287.655 91.44 0)
			(effects
				(font
					(size 1.27 1.27)
				)
			)
		)
		(property "Footprint" ""
			(at 287.655 86.995 0)
			(effects
				(font
					(size 1.27 1.27)
				)
				(hide yes)
			)
		)
		(property "Datasheet" ""
			(at 287.655 86.995 0)
			(effects
				(font
					(size 1.27 1.27)
				)
				(hide yes)
			)
		)
		(property "Description" ""
			(at 287.655 86.995 0)
			(effects
				(font
					(size 1.27 1.27)
				)
			)
		)
		(pin "1"
		)
		(instances
			(project "ddr5-testbed"
				(path ""
					(reference "#PWR07")
					(unit 1)
				)
			)
		)
	)
	(symbol
		(lib_id "antmicropower:GND")
		(at 297.815 86.995 0)
		(unit 1)
		(exclude_from_sim no)
		(in_bom yes)
		(on_board yes)
		(dnp no)
		(fields_autoplaced yes)
		(property "Reference" "#PWR010"
			(at 297.815 93.345 0)
			(effects
				(font
					(size 1.27 1.27)
				)
				(hide yes)
			)
		)
		(property "Value" "GND"
			(at 297.815 91.44 0)
			(effects
				(font
					(size 1.27 1.27)
				)
			)
		)
		(property "Footprint" ""
			(at 297.815 86.995 0)
			(effects
				(font
					(size 1.27 1.27)
				)
				(hide yes)
			)
		)
		(property "Datasheet" ""
			(at 297.815 86.995 0)
			(effects
				(font
					(size 1.27 1.27)
				)
				(hide yes)
			)
		)
		(property "Description" ""
			(at 297.815 86.995 0)
			(effects
				(font
					(size 1.27 1.27)
				)
			)
		)
		(pin "1"
		)
		(instances
			(project "ddr5-testbed"
				(path ""
					(reference "#PWR010")
					(unit 1)
				)
			)
		)
	)
	(symbol
		(lib_id "antmicroCapacitorsmisc:C_100n_0201")
		(at 309.245 81.915 270)
		(unit 1)
		(exclude_from_sim no)
		(in_bom yes)
		(on_board yes)
		(dnp no)
		(fields_autoplaced yes)
		(property "Reference" "C13"
			(at 312.42 83.1913 90)
			(effects
				(font
					(size 1.27 1.27)
				)
				(justify left)
			)
		)
		(property "Value" "C_100n_0201"
			(at 299.085 102.235 0)
			(effects
				(font
					(size 1.27 1.27)
					(thickness 0.15)
				)
				(justify left bottom)
				(hide yes)
			)
		)
		(property "Footprint" "antmicro-footprints:C_0201"
			(at 296.545 102.235 0)
			(effects
				(font
					(size 1.27 1.27)
					(thickness 0.15)
				)
				(justify left bottom)
				(hide yes)
			)
		)
		(property "Datasheet" "https://www.yageo.com/en/Chart/Download/pdf/CC0201KRX6S5BB104"
			(at 294.005 102.235 0)
			(effects
				(font
					(size 1.27 1.27)
					(thickness 0.15)
				)
				(justify left bottom)
				(hide yes)
			)
		)
		(property "Description" ""
			(at 309.245 81.915 0)
			(effects
				(font
					(size 1.27 1.27)
				)
			)
		)
		(property "Manufacturer" "YAGEO"
			(at 288.925 102.235 0)
			(effects
				(font
					(size 1.27 1.27)
					(thickness 0.15)
				)
				(justify left bottom)
				(hide yes)
			)
		)
		(property "MPN" "CC0201KRX6S5BB104"
			(at 291.465 102.235 0)
			(effects
				(font
					(size 1.27 1.27)
					(thickness 0.15)
				)
				(justify left bottom)
				(hide yes)
			)
		)
		(property "Val" "100n"
			(at 312.42 86.3662 90)
			(effects
				(font
					(size 1.27 1.27)
					(thickness 0.15)
				)
				(justify left)
			)
		)
		(property "License" "Apache-2.0"
			(at 286.385 102.235 0)
			(effects
				(font
					(size 1.27 1.27)
					(thickness 0.15)
				)
				(justify left bottom)
				(hide yes)
			)
		)
		(property "Author" "Antmicro"
			(at 283.845 102.235 0)
			(effects
				(font
					(size 1.27 1.27)
					(thickness 0.15)
				)
				(justify left bottom)
				(hide yes)
			)
		)
		(property "Voltage" ""
			(at 281.305 102.235 0)
			(effects
				(font
					(size 1.27 1.27)
				)
				(justify left bottom)
				(hide yes)
			)
		)
		(property "Dielectric" ""
			(at 278.765 102.235 0)
			(effects
				(font
					(size 1.27 1.27)
				)
				(justify left bottom)
				(hide yes)
			)
		)
		(property "Public" "False"
			(at 276.225 102.235 0)
			(effects
				(font
					(size 1.27 1.27)
				)
				(justify left bottom)
				(hide yes)
			)
		)
		(pin "1"
		)
		(pin "2"
		)
		(instances
			(project "ddr5-testbed"
				(path ""
					(reference "C13")
					(unit 1)
				)
			)
		)
	)
	(symbol
		(lib_id "antmicropower:GND")
		(at 309.245 86.995 0)
		(unit 1)
		(exclude_from_sim no)
		(in_bom yes)
		(on_board yes)
		(dnp no)
		(fields_autoplaced yes)
		(property "Reference" "#PWR013"
			(at 309.245 93.345 0)
			(effects
				(font
					(size 1.27 1.27)
				)
				(hide yes)
			)
		)
		(property "Value" "GND"
			(at 309.245 91.44 0)
			(effects
				(font
					(size 1.27 1.27)
				)
			)
		)
		(property "Footprint" ""
			(at 309.245 86.995 0)
			(effects
				(font
					(size 1.27 1.27)
				)
				(hide yes)
			)
		)
		(property "Datasheet" ""
			(at 309.245 86.995 0)
			(effects
				(font
					(size 1.27 1.27)
				)
				(hide yes)
			)
		)
		(property "Description" ""
			(at 309.245 86.995 0)
			(effects
				(font
					(size 1.27 1.27)
				)
			)
		)
		(pin "1"
		)
		(instances
			(project "ddr5-testbed"
				(path ""
					(reference "#PWR013")
					(unit 1)
				)
			)
		)
	)
	(symbol
		(lib_id "antmicroCapacitorsmisc:C_100n_0201")
		(at 265.43 105.41 270)
		(unit 1)
		(exclude_from_sim no)
		(in_bom yes)
		(on_board yes)
		(dnp no)
		(fields_autoplaced yes)
		(property "Reference" "C2"
			(at 267.97 106.6863 90)
			(effects
				(font
					(size 1.27 1.27)
				)
				(justify left)
			)
		)
		(property "Value" "C_100n_0201"
			(at 255.27 125.73 0)
			(effects
				(font
					(size 1.27 1.27)
					(thickness 0.15)
				)
				(justify left bottom)
				(hide yes)
			)
		)
		(property "Footprint" "antmicro-footprints:C_0201"
			(at 252.73 125.73 0)
			(effects
				(font
					(size 1.27 1.27)
					(thickness 0.15)
				)
				(justify left bottom)
				(hide yes)
			)
		)
		(property "Datasheet" "https://www.yageo.com/en/Chart/Download/pdf/CC0201KRX6S5BB104"
			(at 250.19 125.73 0)
			(effects
				(font
					(size 1.27 1.27)
					(thickness 0.15)
				)
				(justify left bottom)
				(hide yes)
			)
		)
		(property "Description" ""
			(at 265.43 105.41 0)
			(effects
				(font
					(size 1.27 1.27)
				)
			)
		)
		(property "Manufacturer" "YAGEO"
			(at 245.11 125.73 0)
			(effects
				(font
					(size 1.27 1.27)
					(thickness 0.15)
				)
				(justify left bottom)
				(hide yes)
			)
		)
		(property "MPN" "CC0201KRX6S5BB104"
			(at 247.65 125.73 0)
			(effects
				(font
					(size 1.27 1.27)
					(thickness 0.15)
				)
				(justify left bottom)
				(hide yes)
			)
		)
		(property "Val" "100n"
			(at 267.97 109.8612 90)
			(effects
				(font
					(size 1.27 1.27)
					(thickness 0.15)
				)
				(justify left)
			)
		)
		(property "License" "Apache-2.0"
			(at 242.57 125.73 0)
			(effects
				(font
					(size 1.27 1.27)
					(thickness 0.15)
				)
				(justify left bottom)
				(hide yes)
			)
		)
		(property "Author" "Antmicro"
			(at 240.03 125.73 0)
			(effects
				(font
					(size 1.27 1.27)
					(thickness 0.15)
				)
				(justify left bottom)
				(hide yes)
			)
		)
		(property "Voltage" ""
			(at 237.49 125.73 0)
			(effects
				(font
					(size 1.27 1.27)
				)
				(justify left bottom)
				(hide yes)
			)
		)
		(property "Dielectric" ""
			(at 234.95 125.73 0)
			(effects
				(font
					(size 1.27 1.27)
				)
				(justify left bottom)
				(hide yes)
			)
		)
		(property "Public" "False"
			(at 232.41 125.73 0)
			(effects
				(font
					(size 1.27 1.27)
				)
				(justify left bottom)
				(hide yes)
			)
		)
		(pin "1"
		)
		(pin "2"
		)
		(instances
			(project "ddr5-testbed"
				(path ""
					(reference "C2")
					(unit 1)
				)
			)
		)
	)
	(symbol
		(lib_id "antmicropower:GND")
		(at 265.43 110.49 0)
		(unit 1)
		(exclude_from_sim no)
		(in_bom yes)
		(on_board yes)
		(dnp no)
		(fields_autoplaced yes)
		(property "Reference" "#PWR02"
			(at 265.43 116.84 0)
			(effects
				(font
					(size 1.27 1.27)
				)
				(hide yes)
			)
		)
		(property "Value" "GND"
			(at 265.43 115.57 0)
			(effects
				(font
					(size 1.27 1.27)
				)
			)
		)
		(property "Footprint" ""
			(at 265.43 110.49 0)
			(effects
				(font
					(size 1.27 1.27)
				)
				(hide yes)
			)
		)
		(property "Datasheet" ""
			(at 265.43 110.49 0)
			(effects
				(font
					(size 1.27 1.27)
				)
				(hide yes)
			)
		)
		(property "Description" ""
			(at 265.43 110.49 0)
			(effects
				(font
					(size 1.27 1.27)
				)
			)
		)
		(pin "1"
		)
		(instances
			(project "ddr5-testbed"
				(path ""
					(reference "#PWR02")
					(unit 1)
				)
			)
		)
	)
	(symbol
		(lib_id "antmicroCapacitorsmisc:C_100n_0201")
		(at 276.86 105.41 270)
		(unit 1)
		(exclude_from_sim no)
		(in_bom yes)
		(on_board yes)
		(dnp no)
		(fields_autoplaced yes)
		(property "Reference" "C5"
			(at 279.4 106.6863 90)
			(effects
				(font
					(size 1.27 1.27)
				)
				(justify left)
			)
		)
		(property "Value" "C_100n_0201"
			(at 266.7 125.73 0)
			(effects
				(font
					(size 1.27 1.27)
					(thickness 0.15)
				)
				(justify left bottom)
				(hide yes)
			)
		)
		(property "Footprint" "antmicro-footprints:C_0201"
			(at 264.16 125.73 0)
			(effects
				(font
					(size 1.27 1.27)
					(thickness 0.15)
				)
				(justify left bottom)
				(hide yes)
			)
		)
		(property "Datasheet" "https://www.yageo.com/en/Chart/Download/pdf/CC0201KRX6S5BB104"
			(at 261.62 125.73 0)
			(effects
				(font
					(size 1.27 1.27)
					(thickness 0.15)
				)
				(justify left bottom)
				(hide yes)
			)
		)
		(property "Description" ""
			(at 276.86 105.41 0)
			(effects
				(font
					(size 1.27 1.27)
				)
			)
		)
		(property "Manufacturer" "YAGEO"
			(at 256.54 125.73 0)
			(effects
				(font
					(size 1.27 1.27)
					(thickness 0.15)
				)
				(justify left bottom)
				(hide yes)
			)
		)
		(property "MPN" "CC0201KRX6S5BB104"
			(at 259.08 125.73 0)
			(effects
				(font
					(size 1.27 1.27)
					(thickness 0.15)
				)
				(justify left bottom)
				(hide yes)
			)
		)
		(property "Val" "100n"
			(at 279.4 109.8612 90)
			(effects
				(font
					(size 1.27 1.27)
					(thickness 0.15)
				)
				(justify left)
			)
		)
		(property "License" "Apache-2.0"
			(at 254 125.73 0)
			(effects
				(font
					(size 1.27 1.27)
					(thickness 0.15)
				)
				(justify left bottom)
				(hide yes)
			)
		)
		(property "Author" "Antmicro"
			(at 251.46 125.73 0)
			(effects
				(font
					(size 1.27 1.27)
					(thickness 0.15)
				)
				(justify left bottom)
				(hide yes)
			)
		)
		(property "Voltage" ""
			(at 248.92 125.73 0)
			(effects
				(font
					(size 1.27 1.27)
				)
				(justify left bottom)
				(hide yes)
			)
		)
		(property "Dielectric" ""
			(at 246.38 125.73 0)
			(effects
				(font
					(size 1.27 1.27)
				)
				(justify left bottom)
				(hide yes)
			)
		)
		(property "Public" "False"
			(at 243.84 125.73 0)
			(effects
				(font
					(size 1.27 1.27)
				)
				(justify left bottom)
				(hide yes)
			)
		)
		(pin "1"
		)
		(pin "2"
		)
		(instances
			(project "ddr5-testbed"
				(path ""
					(reference "C5")
					(unit 1)
				)
			)
		)
	)
	(symbol
		(lib_id "antmicroCapacitorsmisc:C_100n_0201")
		(at 287.655 105.41 270)
		(unit 1)
		(exclude_from_sim no)
		(in_bom yes)
		(on_board yes)
		(dnp no)
		(fields_autoplaced yes)
		(property "Reference" "C8"
			(at 290.83 106.6863 90)
			(effects
				(font
					(size 1.27 1.27)
				)
				(justify left)
			)
		)
		(property "Value" "C_100n_0201"
			(at 277.495 125.73 0)
			(effects
				(font
					(size 1.27 1.27)
					(thickness 0.15)
				)
				(justify left bottom)
				(hide yes)
			)
		)
		(property "Footprint" "antmicro-footprints:C_0201"
			(at 274.955 125.73 0)
			(effects
				(font
					(size 1.27 1.27)
					(thickness 0.15)
				)
				(justify left bottom)
				(hide yes)
			)
		)
		(property "Datasheet" "https://www.yageo.com/en/Chart/Download/pdf/CC0201KRX6S5BB104"
			(at 272.415 125.73 0)
			(effects
				(font
					(size 1.27 1.27)
					(thickness 0.15)
				)
				(justify left bottom)
				(hide yes)
			)
		)
		(property "Description" ""
			(at 287.655 105.41 0)
			(effects
				(font
					(size 1.27 1.27)
				)
			)
		)
		(property "Manufacturer" "YAGEO"
			(at 267.335 125.73 0)
			(effects
				(font
					(size 1.27 1.27)
					(thickness 0.15)
				)
				(justify left bottom)
				(hide yes)
			)
		)
		(property "MPN" "CC0201KRX6S5BB104"
			(at 269.875 125.73 0)
			(effects
				(font
					(size 1.27 1.27)
					(thickness 0.15)
				)
				(justify left bottom)
				(hide yes)
			)
		)
		(property "Val" "100n"
			(at 290.83 109.8612 90)
			(effects
				(font
					(size 1.27 1.27)
					(thickness 0.15)
				)
				(justify left)
			)
		)
		(property "License" "Apache-2.0"
			(at 264.795 125.73 0)
			(effects
				(font
					(size 1.27 1.27)
					(thickness 0.15)
				)
				(justify left bottom)
				(hide yes)
			)
		)
		(property "Author" "Antmicro"
			(at 262.255 125.73 0)
			(effects
				(font
					(size 1.27 1.27)
					(thickness 0.15)
				)
				(justify left bottom)
				(hide yes)
			)
		)
		(property "Voltage" ""
			(at 259.715 125.73 0)
			(effects
				(font
					(size 1.27 1.27)
				)
				(justify left bottom)
				(hide yes)
			)
		)
		(property "Dielectric" ""
			(at 257.175 125.73 0)
			(effects
				(font
					(size 1.27 1.27)
				)
				(justify left bottom)
				(hide yes)
			)
		)
		(property "Public" "False"
			(at 254.635 125.73 0)
			(effects
				(font
					(size 1.27 1.27)
				)
				(justify left bottom)
				(hide yes)
			)
		)
		(pin "1"
		)
		(pin "2"
		)
		(instances
			(project "ddr5-testbed"
				(path ""
					(reference "C8")
					(unit 1)
				)
			)
		)
	)
	(symbol
		(lib_id "antmicroCapacitorsmisc:C_100n_0201")
		(at 297.815 105.41 270)
		(unit 1)
		(exclude_from_sim no)
		(in_bom yes)
		(on_board yes)
		(dnp no)
		(fields_autoplaced yes)
		(property "Reference" "C11"
			(at 300.99 106.6863 90)
			(effects
				(font
					(size 1.27 1.27)
				)
				(justify left)
			)
		)
		(property "Value" "C_100n_0201"
			(at 287.655 125.73 0)
			(effects
				(font
					(size 1.27 1.27)
					(thickness 0.15)
				)
				(justify left bottom)
				(hide yes)
			)
		)
		(property "Footprint" "antmicro-footprints:C_0201"
			(at 285.115 125.73 0)
			(effects
				(font
					(size 1.27 1.27)
					(thickness 0.15)
				)
				(justify left bottom)
				(hide yes)
			)
		)
		(property "Datasheet" "https://www.yageo.com/en/Chart/Download/pdf/CC0201KRX6S5BB104"
			(at 282.575 125.73 0)
			(effects
				(font
					(size 1.27 1.27)
					(thickness 0.15)
				)
				(justify left bottom)
				(hide yes)
			)
		)
		(property "Description" ""
			(at 297.815 105.41 0)
			(effects
				(font
					(size 1.27 1.27)
				)
			)
		)
		(property "Manufacturer" "YAGEO"
			(at 277.495 125.73 0)
			(effects
				(font
					(size 1.27 1.27)
					(thickness 0.15)
				)
				(justify left bottom)
				(hide yes)
			)
		)
		(property "MPN" "CC0201KRX6S5BB104"
			(at 280.035 125.73 0)
			(effects
				(font
					(size 1.27 1.27)
					(thickness 0.15)
				)
				(justify left bottom)
				(hide yes)
			)
		)
		(property "Val" "100n"
			(at 300.99 109.8612 90)
			(effects
				(font
					(size 1.27 1.27)
					(thickness 0.15)
				)
				(justify left)
			)
		)
		(property "License" "Apache-2.0"
			(at 274.955 125.73 0)
			(effects
				(font
					(size 1.27 1.27)
					(thickness 0.15)
				)
				(justify left bottom)
				(hide yes)
			)
		)
		(property "Author" "Antmicro"
			(at 272.415 125.73 0)
			(effects
				(font
					(size 1.27 1.27)
					(thickness 0.15)
				)
				(justify left bottom)
				(hide yes)
			)
		)
		(property "Voltage" ""
			(at 269.875 125.73 0)
			(effects
				(font
					(size 1.27 1.27)
				)
				(justify left bottom)
				(hide yes)
			)
		)
		(property "Dielectric" ""
			(at 267.335 125.73 0)
			(effects
				(font
					(size 1.27 1.27)
				)
				(justify left bottom)
				(hide yes)
			)
		)
		(property "Public" "False"
			(at 264.795 125.73 0)
			(effects
				(font
					(size 1.27 1.27)
				)
				(justify left bottom)
				(hide yes)
			)
		)
		(pin "1"
		)
		(pin "2"
		)
		(instances
			(project "ddr5-testbed"
				(path ""
					(reference "C11")
					(unit 1)
				)
			)
		)
	)
	(symbol
		(lib_id "antmicropower:GND")
		(at 276.86 110.49 0)
		(unit 1)
		(exclude_from_sim no)
		(in_bom yes)
		(on_board yes)
		(dnp no)
		(fields_autoplaced yes)
		(property "Reference" "#PWR05"
			(at 276.86 116.84 0)
			(effects
				(font
					(size 1.27 1.27)
				)
				(hide yes)
			)
		)
		(property "Value" "GND"
			(at 276.86 115.57 0)
			(effects
				(font
					(size 1.27 1.27)
				)
			)
		)
		(property "Footprint" ""
			(at 276.86 110.49 0)
			(effects
				(font
					(size 1.27 1.27)
				)
				(hide yes)
			)
		)
		(property "Datasheet" ""
			(at 276.86 110.49 0)
			(effects
				(font
					(size 1.27 1.27)
				)
				(hide yes)
			)
		)
		(property "Description" ""
			(at 276.86 110.49 0)
			(effects
				(font
					(size 1.27 1.27)
				)
			)
		)
		(pin "1"
		)
		(instances
			(project "ddr5-testbed"
				(path ""
					(reference "#PWR05")
					(unit 1)
				)
			)
		)
	)
	(symbol
		(lib_id "antmicropower:GND")
		(at 287.655 110.49 0)
		(unit 1)
		(exclude_from_sim no)
		(in_bom yes)
		(on_board yes)
		(dnp no)
		(fields_autoplaced yes)
		(property "Reference" "#PWR08"
			(at 287.655 116.84 0)
			(effects
				(font
					(size 1.27 1.27)
				)
				(hide yes)
			)
		)
		(property "Value" "GND"
			(at 287.655 115.57 0)
			(effects
				(font
					(size 1.27 1.27)
				)
			)
		)
		(property "Footprint" ""
			(at 287.655 110.49 0)
			(effects
				(font
					(size 1.27 1.27)
				)
				(hide yes)
			)
		)
		(property "Datasheet" ""
			(at 287.655 110.49 0)
			(effects
				(font
					(size 1.27 1.27)
				)
				(hide yes)
			)
		)
		(property "Description" ""
			(at 287.655 110.49 0)
			(effects
				(font
					(size 1.27 1.27)
				)
			)
		)
		(pin "1"
		)
		(instances
			(project "ddr5-testbed"
				(path ""
					(reference "#PWR08")
					(unit 1)
				)
			)
		)
	)
	(symbol
		(lib_id "antmicropower:GND")
		(at 297.815 110.49 0)
		(unit 1)
		(exclude_from_sim no)
		(in_bom yes)
		(on_board yes)
		(dnp no)
		(fields_autoplaced yes)
		(property "Reference" "#PWR011"
			(at 297.815 116.84 0)
			(effects
				(font
					(size 1.27 1.27)
				)
				(hide yes)
			)
		)
		(property "Value" "GND"
			(at 297.815 115.57 0)
			(effects
				(font
					(size 1.27 1.27)
				)
			)
		)
		(property "Footprint" ""
			(at 297.815 110.49 0)
			(effects
				(font
					(size 1.27 1.27)
				)
				(hide yes)
			)
		)
		(property "Datasheet" ""
			(at 297.815 110.49 0)
			(effects
				(font
					(size 1.27 1.27)
				)
				(hide yes)
			)
		)
		(property "Description" ""
			(at 297.815 110.49 0)
			(effects
				(font
					(size 1.27 1.27)
				)
			)
		)
		(pin "1"
		)
		(instances
			(project "ddr5-testbed"
				(path ""
					(reference "#PWR011")
					(unit 1)
				)
			)
		)
	)
	(symbol
		(lib_id "antmicroCapacitorsmisc:C_100n_0201")
		(at 309.245 105.41 270)
		(unit 1)
		(exclude_from_sim no)
		(in_bom yes)
		(on_board yes)
		(dnp no)
		(fields_autoplaced yes)
		(property "Reference" "C14"
			(at 312.42 106.6863 90)
			(effects
				(font
					(size 1.27 1.27)
				)
				(justify left)
			)
		)
		(property "Value" "C_100n_0201"
			(at 299.085 125.73 0)
			(effects
				(font
					(size 1.27 1.27)
					(thickness 0.15)
				)
				(justify left bottom)
				(hide yes)
			)
		)
		(property "Footprint" "antmicro-footprints:C_0201"
			(at 296.545 125.73 0)
			(effects
				(font
					(size 1.27 1.27)
					(thickness 0.15)
				)
				(justify left bottom)
				(hide yes)
			)
		)
		(property "Datasheet" "https://www.yageo.com/en/Chart/Download/pdf/CC0201KRX6S5BB104"
			(at 294.005 125.73 0)
			(effects
				(font
					(size 1.27 1.27)
					(thickness 0.15)
				)
				(justify left bottom)
				(hide yes)
			)
		)
		(property "Description" ""
			(at 309.245 105.41 0)
			(effects
				(font
					(size 1.27 1.27)
				)
			)
		)
		(property "Manufacturer" "YAGEO"
			(at 288.925 125.73 0)
			(effects
				(font
					(size 1.27 1.27)
					(thickness 0.15)
				)
				(justify left bottom)
				(hide yes)
			)
		)
		(property "MPN" "CC0201KRX6S5BB104"
			(at 291.465 125.73 0)
			(effects
				(font
					(size 1.27 1.27)
					(thickness 0.15)
				)
				(justify left bottom)
				(hide yes)
			)
		)
		(property "Val" "100n"
			(at 312.42 109.8612 90)
			(effects
				(font
					(size 1.27 1.27)
					(thickness 0.15)
				)
				(justify left)
			)
		)
		(property "License" "Apache-2.0"
			(at 286.385 125.73 0)
			(effects
				(font
					(size 1.27 1.27)
					(thickness 0.15)
				)
				(justify left bottom)
				(hide yes)
			)
		)
		(property "Author" "Antmicro"
			(at 283.845 125.73 0)
			(effects
				(font
					(size 1.27 1.27)
					(thickness 0.15)
				)
				(justify left bottom)
				(hide yes)
			)
		)
		(property "Voltage" ""
			(at 281.305 125.73 0)
			(effects
				(font
					(size 1.27 1.27)
				)
				(justify left bottom)
				(hide yes)
			)
		)
		(property "Dielectric" ""
			(at 278.765 125.73 0)
			(effects
				(font
					(size 1.27 1.27)
				)
				(justify left bottom)
				(hide yes)
			)
		)
		(property "Public" "False"
			(at 276.225 125.73 0)
			(effects
				(font
					(size 1.27 1.27)
				)
				(justify left bottom)
				(hide yes)
			)
		)
		(pin "1"
		)
		(pin "2"
		)
		(instances
			(project "ddr5-testbed"
				(path ""
					(reference "C14")
					(unit 1)
				)
			)
		)
	)
	(symbol
		(lib_id "antmicropower:GND")
		(at 309.245 110.49 0)
		(unit 1)
		(exclude_from_sim no)
		(in_bom yes)
		(on_board yes)
		(dnp no)
		(fields_autoplaced yes)
		(property "Reference" "#PWR014"
			(at 309.245 116.84 0)
			(effects
				(font
					(size 1.27 1.27)
				)
				(hide yes)
			)
		)
		(property "Value" "GND"
			(at 309.245 115.57 0)
			(effects
				(font
					(size 1.27 1.27)
				)
			)
		)
		(property "Footprint" ""
			(at 309.245 110.49 0)
			(effects
				(font
					(size 1.27 1.27)
				)
				(hide yes)
			)
		)
		(property "Datasheet" ""
			(at 309.245 110.49 0)
			(effects
				(font
					(size 1.27 1.27)
				)
				(hide yes)
			)
		)
		(property "Description" ""
			(at 309.245 110.49 0)
			(effects
				(font
					(size 1.27 1.27)
				)
			)
		)
		(pin "1"
		)
		(instances
			(project "ddr5-testbed"
				(path ""
					(reference "#PWR014")
					(unit 1)
				)
			)
		)
	)
	(symbol
		(lib_id "antmicroCapacitorsmisc:C_100n_0201")
		(at 184.15 81.915 270)
		(unit 1)
		(exclude_from_sim no)
		(in_bom yes)
		(on_board yes)
		(dnp no)
		(fields_autoplaced yes)
		(property "Reference" "C24"
			(at 187.325 83.1913 90)
			(effects
				(font
					(size 1.27 1.27)
				)
				(justify left)
			)
		)
		(property "Value" "C_100n_0201"
			(at 173.99 102.235 0)
			(effects
				(font
					(size 1.27 1.27)
					(thickness 0.15)
				)
				(justify left bottom)
				(hide yes)
			)
		)
		(property "Footprint" "antmicro-footprints:C_0201"
			(at 171.45 102.235 0)
			(effects
				(font
					(size 1.27 1.27)
					(thickness 0.15)
				)
				(justify left bottom)
				(hide yes)
			)
		)
		(property "Datasheet" "https://www.yageo.com/en/Chart/Download/pdf/CC0201KRX6S5BB104"
			(at 168.91 102.235 0)
			(effects
				(font
					(size 1.27 1.27)
					(thickness 0.15)
				)
				(justify left bottom)
				(hide yes)
			)
		)
		(property "Description" ""
			(at 184.15 81.915 0)
			(effects
				(font
					(size 1.27 1.27)
				)
			)
		)
		(property "Manufacturer" "YAGEO"
			(at 163.83 102.235 0)
			(effects
				(font
					(size 1.27 1.27)
					(thickness 0.15)
				)
				(justify left bottom)
				(hide yes)
			)
		)
		(property "MPN" "CC0201KRX6S5BB104"
			(at 166.37 102.235 0)
			(effects
				(font
					(size 1.27 1.27)
					(thickness 0.15)
				)
				(justify left bottom)
				(hide yes)
			)
		)
		(property "Val" "100n"
			(at 187.325 86.3662 90)
			(effects
				(font
					(size 1.27 1.27)
					(thickness 0.15)
				)
				(justify left)
			)
		)
		(property "License" "Apache-2.0"
			(at 161.29 102.235 0)
			(effects
				(font
					(size 1.27 1.27)
					(thickness 0.15)
				)
				(justify left bottom)
				(hide yes)
			)
		)
		(property "Author" "Antmicro"
			(at 158.75 102.235 0)
			(effects
				(font
					(size 1.27 1.27)
					(thickness 0.15)
				)
				(justify left bottom)
				(hide yes)
			)
		)
		(property "Voltage" ""
			(at 156.21 102.235 0)
			(effects
				(font
					(size 1.27 1.27)
				)
				(justify left bottom)
				(hide yes)
			)
		)
		(property "Dielectric" ""
			(at 153.67 102.235 0)
			(effects
				(font
					(size 1.27 1.27)
				)
				(justify left bottom)
				(hide yes)
			)
		)
		(property "Public" "False"
			(at 151.13 102.235 0)
			(effects
				(font
					(size 1.27 1.27)
				)
				(justify left bottom)
				(hide yes)
			)
		)
		(pin "1"
		)
		(pin "2"
		)
		(instances
			(project "ddr5-testbed"
				(path ""
					(reference "C24")
					(unit 1)
				)
			)
		)
	)
	(symbol
		(lib_id "antmicropower:GND")
		(at 184.15 86.995 0)
		(unit 1)
		(exclude_from_sim no)
		(in_bom yes)
		(on_board yes)
		(dnp no)
		(fields_autoplaced yes)
		(property "Reference" "#PWR025"
			(at 184.15 93.345 0)
			(effects
				(font
					(size 1.27 1.27)
				)
				(hide yes)
			)
		)
		(property "Value" "GND"
			(at 184.15 91.44 0)
			(effects
				(font
					(size 1.27 1.27)
				)
			)
		)
		(property "Footprint" ""
			(at 184.15 86.995 0)
			(effects
				(font
					(size 1.27 1.27)
				)
				(hide yes)
			)
		)
		(property "Datasheet" ""
			(at 184.15 86.995 0)
			(effects
				(font
					(size 1.27 1.27)
				)
				(hide yes)
			)
		)
		(property "Description" ""
			(at 184.15 86.995 0)
			(effects
				(font
					(size 1.27 1.27)
				)
			)
		)
		(pin "1"
		)
		(instances
			(project "ddr5-testbed"
				(path ""
					(reference "#PWR025")
					(unit 1)
				)
			)
		)
	)
	(symbol
		(lib_id "antmicroCapacitorsmisc:C_100n_0201")
		(at 194.31 81.915 270)
		(unit 1)
		(exclude_from_sim no)
		(in_bom yes)
		(on_board yes)
		(dnp no)
		(fields_autoplaced yes)
		(property "Reference" "C25"
			(at 197.485 83.1913 90)
			(effects
				(font
					(size 1.27 1.27)
				)
				(justify left)
			)
		)
		(property "Value" "C_100n_0201"
			(at 184.15 102.235 0)
			(effects
				(font
					(size 1.27 1.27)
					(thickness 0.15)
				)
				(justify left bottom)
				(hide yes)
			)
		)
		(property "Footprint" "antmicro-footprints:C_0201"
			(at 181.61 102.235 0)
			(effects
				(font
					(size 1.27 1.27)
					(thickness 0.15)
				)
				(justify left bottom)
				(hide yes)
			)
		)
		(property "Datasheet" "https://www.yageo.com/en/Chart/Download/pdf/CC0201KRX6S5BB104"
			(at 179.07 102.235 0)
			(effects
				(font
					(size 1.27 1.27)
					(thickness 0.15)
				)
				(justify left bottom)
				(hide yes)
			)
		)
		(property "Description" ""
			(at 194.31 81.915 0)
			(effects
				(font
					(size 1.27 1.27)
				)
			)
		)
		(property "Manufacturer" "YAGEO"
			(at 173.99 102.235 0)
			(effects
				(font
					(size 1.27 1.27)
					(thickness 0.15)
				)
				(justify left bottom)
				(hide yes)
			)
		)
		(property "MPN" "CC0201KRX6S5BB104"
			(at 176.53 102.235 0)
			(effects
				(font
					(size 1.27 1.27)
					(thickness 0.15)
				)
				(justify left bottom)
				(hide yes)
			)
		)
		(property "Val" "100n"
			(at 197.485 86.3662 90)
			(effects
				(font
					(size 1.27 1.27)
					(thickness 0.15)
				)
				(justify left)
			)
		)
		(property "License" "Apache-2.0"
			(at 171.45 102.235 0)
			(effects
				(font
					(size 1.27 1.27)
					(thickness 0.15)
				)
				(justify left bottom)
				(hide yes)
			)
		)
		(property "Author" "Antmicro"
			(at 168.91 102.235 0)
			(effects
				(font
					(size 1.27 1.27)
					(thickness 0.15)
				)
				(justify left bottom)
				(hide yes)
			)
		)
		(property "Voltage" ""
			(at 166.37 102.235 0)
			(effects
				(font
					(size 1.27 1.27)
				)
				(justify left bottom)
				(hide yes)
			)
		)
		(property "Dielectric" ""
			(at 163.83 102.235 0)
			(effects
				(font
					(size 1.27 1.27)
				)
				(justify left bottom)
				(hide yes)
			)
		)
		(property "Public" "False"
			(at 161.29 102.235 0)
			(effects
				(font
					(size 1.27 1.27)
				)
				(justify left bottom)
				(hide yes)
			)
		)
		(pin "1"
		)
		(pin "2"
		)
		(instances
			(project "ddr5-testbed"
				(path ""
					(reference "C25")
					(unit 1)
				)
			)
		)
	)
	(symbol
		(lib_id "antmicropower:GND")
		(at 194.31 86.995 0)
		(unit 1)
		(exclude_from_sim no)
		(in_bom yes)
		(on_board yes)
		(dnp no)
		(fields_autoplaced yes)
		(property "Reference" "#PWR026"
			(at 194.31 93.345 0)
			(effects
				(font
					(size 1.27 1.27)
				)
				(hide yes)
			)
		)
		(property "Value" "GND"
			(at 194.31 91.44 0)
			(effects
				(font
					(size 1.27 1.27)
				)
			)
		)
		(property "Footprint" ""
			(at 194.31 86.995 0)
			(effects
				(font
					(size 1.27 1.27)
				)
				(hide yes)
			)
		)
		(property "Datasheet" ""
			(at 194.31 86.995 0)
			(effects
				(font
					(size 1.27 1.27)
				)
				(hide yes)
			)
		)
		(property "Description" ""
			(at 194.31 86.995 0)
			(effects
				(font
					(size 1.27 1.27)
				)
			)
		)
		(pin "1"
		)
		(instances
			(project "ddr5-testbed"
				(path ""
					(reference "#PWR026")
					(unit 1)
				)
			)
		)
	)
	(symbol
		(lib_id "antmicroCapacitorsmisc:C_100n_0201")
		(at 80.01 81.915 270)
		(unit 1)
		(exclude_from_sim no)
		(in_bom yes)
		(on_board yes)
		(dnp no)
		(fields_autoplaced yes)
		(property "Reference" "C3"
			(at 82.55 83.1913 90)
			(effects
				(font
					(size 1.27 1.27)
				)
				(justify left)
			)
		)
		(property "Value" "C_100n_0201"
			(at 69.85 102.235 0)
			(effects
				(font
					(size 1.27 1.27)
					(thickness 0.15)
				)
				(justify left bottom)
				(hide yes)
			)
		)
		(property "Footprint" "antmicro-footprints:C_0201"
			(at 67.31 102.235 0)
			(effects
				(font
					(size 1.27 1.27)
					(thickness 0.15)
				)
				(justify left bottom)
				(hide yes)
			)
		)
		(property "Datasheet" "https://www.yageo.com/en/Chart/Download/pdf/CC0201KRX6S5BB104"
			(at 64.77 102.235 0)
			(effects
				(font
					(size 1.27 1.27)
					(thickness 0.15)
				)
				(justify left bottom)
				(hide yes)
			)
		)
		(property "Description" ""
			(at 80.01 81.915 0)
			(effects
				(font
					(size 1.27 1.27)
				)
			)
		)
		(property "Manufacturer" "YAGEO"
			(at 59.69 102.235 0)
			(effects
				(font
					(size 1.27 1.27)
					(thickness 0.15)
				)
				(justify left bottom)
				(hide yes)
			)
		)
		(property "MPN" "CC0201KRX6S5BB104"
			(at 62.23 102.235 0)
			(effects
				(font
					(size 1.27 1.27)
					(thickness 0.15)
				)
				(justify left bottom)
				(hide yes)
			)
		)
		(property "Val" "100n"
			(at 82.55 86.3662 90)
			(effects
				(font
					(size 1.27 1.27)
					(thickness 0.15)
				)
				(justify left)
			)
		)
		(property "License" "Apache-2.0"
			(at 57.15 102.235 0)
			(effects
				(font
					(size 1.27 1.27)
					(thickness 0.15)
				)
				(justify left bottom)
				(hide yes)
			)
		)
		(property "Author" "Antmicro"
			(at 54.61 102.235 0)
			(effects
				(font
					(size 1.27 1.27)
					(thickness 0.15)
				)
				(justify left bottom)
				(hide yes)
			)
		)
		(property "Voltage" ""
			(at 52.07 102.235 0)
			(effects
				(font
					(size 1.27 1.27)
				)
				(justify left bottom)
				(hide yes)
			)
		)
		(property "Dielectric" ""
			(at 49.53 102.235 0)
			(effects
				(font
					(size 1.27 1.27)
				)
				(justify left bottom)
				(hide yes)
			)
		)
		(property "Public" "False"
			(at 46.99 102.235 0)
			(effects
				(font
					(size 1.27 1.27)
				)
				(justify left bottom)
				(hide yes)
			)
		)
		(pin "1"
		)
		(pin "2"
		)
		(instances
			(project "ddr5-testbed"
				(path ""
					(reference "C3")
					(unit 1)
				)
			)
		)
	)
	(symbol
		(lib_id "antmicropower:GND")
		(at 80.01 86.995 0)
		(unit 1)
		(exclude_from_sim no)
		(in_bom yes)
		(on_board yes)
		(dnp no)
		(fields_autoplaced yes)
		(property "Reference" "#PWR03"
			(at 80.01 93.345 0)
			(effects
				(font
					(size 1.27 1.27)
				)
				(hide yes)
			)
		)
		(property "Value" "GND"
			(at 80.01 91.44 0)
			(effects
				(font
					(size 1.27 1.27)
				)
			)
		)
		(property "Footprint" ""
			(at 80.01 86.995 0)
			(effects
				(font
					(size 1.27 1.27)
				)
				(hide yes)
			)
		)
		(property "Datasheet" ""
			(at 80.01 86.995 0)
			(effects
				(font
					(size 1.27 1.27)
				)
				(hide yes)
			)
		)
		(property "Description" ""
			(at 80.01 86.995 0)
			(effects
				(font
					(size 1.27 1.27)
				)
			)
		)
		(pin "1"
		)
		(instances
			(project "ddr5-testbed"
				(path ""
					(reference "#PWR03")
					(unit 1)
				)
			)
		)
	)
	(symbol
		(lib_id "antmicroCapacitorsmisc:C_100n_0201")
		(at 91.44 81.915 270)
		(unit 1)
		(exclude_from_sim no)
		(in_bom yes)
		(on_board yes)
		(dnp no)
		(fields_autoplaced yes)
		(property "Reference" "C6"
			(at 94.615 83.1913 90)
			(effects
				(font
					(size 1.27 1.27)
				)
				(justify left)
			)
		)
		(property "Value" "C_100n_0201"
			(at 81.28 102.235 0)
			(effects
				(font
					(size 1.27 1.27)
					(thickness 0.15)
				)
				(justify left bottom)
				(hide yes)
			)
		)
		(property "Footprint" "antmicro-footprints:C_0201"
			(at 78.74 102.235 0)
			(effects
				(font
					(size 1.27 1.27)
					(thickness 0.15)
				)
				(justify left bottom)
				(hide yes)
			)
		)
		(property "Datasheet" "https://www.yageo.com/en/Chart/Download/pdf/CC0201KRX6S5BB104"
			(at 76.2 102.235 0)
			(effects
				(font
					(size 1.27 1.27)
					(thickness 0.15)
				)
				(justify left bottom)
				(hide yes)
			)
		)
		(property "Description" ""
			(at 91.44 81.915 0)
			(effects
				(font
					(size 1.27 1.27)
				)
			)
		)
		(property "Manufacturer" "YAGEO"
			(at 71.12 102.235 0)
			(effects
				(font
					(size 1.27 1.27)
					(thickness 0.15)
				)
				(justify left bottom)
				(hide yes)
			)
		)
		(property "MPN" "CC0201KRX6S5BB104"
			(at 73.66 102.235 0)
			(effects
				(font
					(size 1.27 1.27)
					(thickness 0.15)
				)
				(justify left bottom)
				(hide yes)
			)
		)
		(property "Val" "100n"
			(at 94.615 86.3662 90)
			(effects
				(font
					(size 1.27 1.27)
					(thickness 0.15)
				)
				(justify left)
			)
		)
		(property "License" "Apache-2.0"
			(at 68.58 102.235 0)
			(effects
				(font
					(size 1.27 1.27)
					(thickness 0.15)
				)
				(justify left bottom)
				(hide yes)
			)
		)
		(property "Author" "Antmicro"
			(at 66.04 102.235 0)
			(effects
				(font
					(size 1.27 1.27)
					(thickness 0.15)
				)
				(justify left bottom)
				(hide yes)
			)
		)
		(property "Voltage" ""
			(at 63.5 102.235 0)
			(effects
				(font
					(size 1.27 1.27)
				)
				(justify left bottom)
				(hide yes)
			)
		)
		(property "Dielectric" ""
			(at 60.96 102.235 0)
			(effects
				(font
					(size 1.27 1.27)
				)
				(justify left bottom)
				(hide yes)
			)
		)
		(property "Public" "False"
			(at 58.42 102.235 0)
			(effects
				(font
					(size 1.27 1.27)
				)
				(justify left bottom)
				(hide yes)
			)
		)
		(pin "1"
		)
		(pin "2"
		)
		(instances
			(project "ddr5-testbed"
				(path ""
					(reference "C6")
					(unit 1)
				)
			)
		)
	)
	(symbol
		(lib_id "antmicropower:GND")
		(at 91.44 86.995 0)
		(unit 1)
		(exclude_from_sim no)
		(in_bom yes)
		(on_board yes)
		(dnp no)
		(fields_autoplaced yes)
		(property "Reference" "#PWR06"
			(at 91.44 93.345 0)
			(effects
				(font
					(size 1.27 1.27)
				)
				(hide yes)
			)
		)
		(property "Value" "GND"
			(at 91.44 91.44 0)
			(effects
				(font
					(size 1.27 1.27)
				)
			)
		)
		(property "Footprint" ""
			(at 91.44 86.995 0)
			(effects
				(font
					(size 1.27 1.27)
				)
				(hide yes)
			)
		)
		(property "Datasheet" ""
			(at 91.44 86.995 0)
			(effects
				(font
					(size 1.27 1.27)
				)
				(hide yes)
			)
		)
		(property "Description" ""
			(at 91.44 86.995 0)
			(effects
				(font
					(size 1.27 1.27)
				)
			)
		)
		(pin "1"
		)
		(instances
			(project "ddr5-testbed"
				(path ""
					(reference "#PWR06")
					(unit 1)
				)
			)
		)
	)
	(symbol
		(lib_id "antmicroCapacitorsmisc:C_100n_0201")
		(at 102.87 81.915 270)
		(unit 1)
		(exclude_from_sim no)
		(in_bom yes)
		(on_board yes)
		(dnp no)
		(fields_autoplaced yes)
		(property "Reference" "C9"
			(at 105.41 83.1913 90)
			(effects
				(font
					(size 1.27 1.27)
				)
				(justify left)
			)
		)
		(property "Value" "C_100n_0201"
			(at 92.71 102.235 0)
			(effects
				(font
					(size 1.27 1.27)
					(thickness 0.15)
				)
				(justify left bottom)
				(hide yes)
			)
		)
		(property "Footprint" "antmicro-footprints:C_0201"
			(at 90.17 102.235 0)
			(effects
				(font
					(size 1.27 1.27)
					(thickness 0.15)
				)
				(justify left bottom)
				(hide yes)
			)
		)
		(property "Datasheet" "https://www.yageo.com/en/Chart/Download/pdf/CC0201KRX6S5BB104"
			(at 87.63 102.235 0)
			(effects
				(font
					(size 1.27 1.27)
					(thickness 0.15)
				)
				(justify left bottom)
				(hide yes)
			)
		)
		(property "Description" ""
			(at 102.87 81.915 0)
			(effects
				(font
					(size 1.27 1.27)
				)
			)
		)
		(property "Manufacturer" "YAGEO"
			(at 82.55 102.235 0)
			(effects
				(font
					(size 1.27 1.27)
					(thickness 0.15)
				)
				(justify left bottom)
				(hide yes)
			)
		)
		(property "MPN" "CC0201KRX6S5BB104"
			(at 85.09 102.235 0)
			(effects
				(font
					(size 1.27 1.27)
					(thickness 0.15)
				)
				(justify left bottom)
				(hide yes)
			)
		)
		(property "Val" "100n"
			(at 105.41 86.3662 90)
			(effects
				(font
					(size 1.27 1.27)
					(thickness 0.15)
				)
				(justify left)
			)
		)
		(property "License" "Apache-2.0"
			(at 80.01 102.235 0)
			(effects
				(font
					(size 1.27 1.27)
					(thickness 0.15)
				)
				(justify left bottom)
				(hide yes)
			)
		)
		(property "Author" "Antmicro"
			(at 77.47 102.235 0)
			(effects
				(font
					(size 1.27 1.27)
					(thickness 0.15)
				)
				(justify left bottom)
				(hide yes)
			)
		)
		(property "Voltage" ""
			(at 74.93 102.235 0)
			(effects
				(font
					(size 1.27 1.27)
				)
				(justify left bottom)
				(hide yes)
			)
		)
		(property "Dielectric" ""
			(at 72.39 102.235 0)
			(effects
				(font
					(size 1.27 1.27)
				)
				(justify left bottom)
				(hide yes)
			)
		)
		(property "Public" "False"
			(at 69.85 102.235 0)
			(effects
				(font
					(size 1.27 1.27)
				)
				(justify left bottom)
				(hide yes)
			)
		)
		(pin "1"
		)
		(pin "2"
		)
		(instances
			(project "ddr5-testbed"
				(path ""
					(reference "C9")
					(unit 1)
				)
			)
		)
	)
	(symbol
		(lib_id "antmicropower:GND")
		(at 102.87 86.995 0)
		(unit 1)
		(exclude_from_sim no)
		(in_bom yes)
		(on_board yes)
		(dnp no)
		(fields_autoplaced yes)
		(property "Reference" "#PWR09"
			(at 102.87 93.345 0)
			(effects
				(font
					(size 1.27 1.27)
				)
				(hide yes)
			)
		)
		(property "Value" "GND"
			(at 102.87 91.44 0)
			(effects
				(font
					(size 1.27 1.27)
				)
			)
		)
		(property "Footprint" ""
			(at 102.87 86.995 0)
			(effects
				(font
					(size 1.27 1.27)
				)
				(hide yes)
			)
		)
		(property "Datasheet" ""
			(at 102.87 86.995 0)
			(effects
				(font
					(size 1.27 1.27)
				)
				(hide yes)
			)
		)
		(property "Description" ""
			(at 102.87 86.995 0)
			(effects
				(font
					(size 1.27 1.27)
				)
			)
		)
		(pin "1"
		)
		(instances
			(project "ddr5-testbed"
				(path ""
					(reference "#PWR09")
					(unit 1)
				)
			)
		)
	)
	(symbol
		(lib_id "antmicroCapacitorsmisc:C_100n_0201")
		(at 114.3 81.915 270)
		(unit 1)
		(exclude_from_sim no)
		(in_bom yes)
		(on_board yes)
		(dnp no)
		(fields_autoplaced yes)
		(property "Reference" "C12"
			(at 116.84 83.1913 90)
			(effects
				(font
					(size 1.27 1.27)
				)
				(justify left)
			)
		)
		(property "Value" "C_100n_0201"
			(at 104.14 102.235 0)
			(effects
				(font
					(size 1.27 1.27)
					(thickness 0.15)
				)
				(justify left bottom)
				(hide yes)
			)
		)
		(property "Footprint" "antmicro-footprints:C_0201"
			(at 101.6 102.235 0)
			(effects
				(font
					(size 1.27 1.27)
					(thickness 0.15)
				)
				(justify left bottom)
				(hide yes)
			)
		)
		(property "Datasheet" "https://www.yageo.com/en/Chart/Download/pdf/CC0201KRX6S5BB104"
			(at 99.06 102.235 0)
			(effects
				(font
					(size 1.27 1.27)
					(thickness 0.15)
				)
				(justify left bottom)
				(hide yes)
			)
		)
		(property "Description" ""
			(at 114.3 81.915 0)
			(effects
				(font
					(size 1.27 1.27)
				)
			)
		)
		(property "Manufacturer" "YAGEO"
			(at 93.98 102.235 0)
			(effects
				(font
					(size 1.27 1.27)
					(thickness 0.15)
				)
				(justify left bottom)
				(hide yes)
			)
		)
		(property "MPN" "CC0201KRX6S5BB104"
			(at 96.52 102.235 0)
			(effects
				(font
					(size 1.27 1.27)
					(thickness 0.15)
				)
				(justify left bottom)
				(hide yes)
			)
		)
		(property "Val" "100n"
			(at 116.84 86.3662 90)
			(effects
				(font
					(size 1.27 1.27)
					(thickness 0.15)
				)
				(justify left)
			)
		)
		(property "License" "Apache-2.0"
			(at 91.44 102.235 0)
			(effects
				(font
					(size 1.27 1.27)
					(thickness 0.15)
				)
				(justify left bottom)
				(hide yes)
			)
		)
		(property "Author" "Antmicro"
			(at 88.9 102.235 0)
			(effects
				(font
					(size 1.27 1.27)
					(thickness 0.15)
				)
				(justify left bottom)
				(hide yes)
			)
		)
		(property "Voltage" ""
			(at 86.36 102.235 0)
			(effects
				(font
					(size 1.27 1.27)
				)
				(justify left bottom)
				(hide yes)
			)
		)
		(property "Dielectric" ""
			(at 83.82 102.235 0)
			(effects
				(font
					(size 1.27 1.27)
				)
				(justify left bottom)
				(hide yes)
			)
		)
		(property "Public" "False"
			(at 81.28 102.235 0)
			(effects
				(font
					(size 1.27 1.27)
				)
				(justify left bottom)
				(hide yes)
			)
		)
		(pin "1"
		)
		(pin "2"
		)
		(instances
			(project "ddr5-testbed"
				(path ""
					(reference "C12")
					(unit 1)
				)
			)
		)
	)
	(symbol
		(lib_id "antmicropower:GND")
		(at 114.3 86.995 0)
		(unit 1)
		(exclude_from_sim no)
		(in_bom yes)
		(on_board yes)
		(dnp no)
		(fields_autoplaced yes)
		(property "Reference" "#PWR012"
			(at 114.3 93.345 0)
			(effects
				(font
					(size 1.27 1.27)
				)
				(hide yes)
			)
		)
		(property "Value" "GND"
			(at 114.3 91.44 0)
			(effects
				(font
					(size 1.27 1.27)
				)
			)
		)
		(property "Footprint" ""
			(at 114.3 86.995 0)
			(effects
				(font
					(size 1.27 1.27)
				)
				(hide yes)
			)
		)
		(property "Datasheet" ""
			(at 114.3 86.995 0)
			(effects
				(font
					(size 1.27 1.27)
				)
				(hide yes)
			)
		)
		(property "Description" ""
			(at 114.3 86.995 0)
			(effects
				(font
					(size 1.27 1.27)
				)
			)
		)
		(pin "1"
		)
		(instances
			(project "ddr5-testbed"
				(path ""
					(reference "#PWR012")
					(unit 1)
				)
			)
		)
	)
	(symbol
		(lib_id "antmicroCapacitorsmisc:C_100n_0201")
		(at 125.73 81.915 270)
		(unit 1)
		(exclude_from_sim no)
		(in_bom yes)
		(on_board yes)
		(dnp no)
		(fields_autoplaced yes)
		(property "Reference" "C15"
			(at 128.905 83.1913 90)
			(effects
				(font
					(size 1.27 1.27)
				)
				(justify left)
			)
		)
		(property "Value" "C_100n_0201"
			(at 115.57 102.235 0)
			(effects
				(font
					(size 1.27 1.27)
					(thickness 0.15)
				)
				(justify left bottom)
				(hide yes)
			)
		)
		(property "Footprint" "antmicro-footprints:C_0201"
			(at 113.03 102.235 0)
			(effects
				(font
					(size 1.27 1.27)
					(thickness 0.15)
				)
				(justify left bottom)
				(hide yes)
			)
		)
		(property "Datasheet" "https://www.yageo.com/en/Chart/Download/pdf/CC0201KRX6S5BB104"
			(at 110.49 102.235 0)
			(effects
				(font
					(size 1.27 1.27)
					(thickness 0.15)
				)
				(justify left bottom)
				(hide yes)
			)
		)
		(property "Description" ""
			(at 125.73 81.915 0)
			(effects
				(font
					(size 1.27 1.27)
				)
			)
		)
		(property "Manufacturer" "YAGEO"
			(at 105.41 102.235 0)
			(effects
				(font
					(size 1.27 1.27)
					(thickness 0.15)
				)
				(justify left bottom)
				(hide yes)
			)
		)
		(property "MPN" "CC0201KRX6S5BB104"
			(at 107.95 102.235 0)
			(effects
				(font
					(size 1.27 1.27)
					(thickness 0.15)
				)
				(justify left bottom)
				(hide yes)
			)
		)
		(property "Val" "100n"
			(at 128.905 86.3662 90)
			(effects
				(font
					(size 1.27 1.27)
					(thickness 0.15)
				)
				(justify left)
			)
		)
		(property "License" "Apache-2.0"
			(at 102.87 102.235 0)
			(effects
				(font
					(size 1.27 1.27)
					(thickness 0.15)
				)
				(justify left bottom)
				(hide yes)
			)
		)
		(property "Author" "Antmicro"
			(at 100.33 102.235 0)
			(effects
				(font
					(size 1.27 1.27)
					(thickness 0.15)
				)
				(justify left bottom)
				(hide yes)
			)
		)
		(property "Voltage" ""
			(at 97.79 102.235 0)
			(effects
				(font
					(size 1.27 1.27)
				)
				(justify left bottom)
				(hide yes)
			)
		)
		(property "Dielectric" ""
			(at 95.25 102.235 0)
			(effects
				(font
					(size 1.27 1.27)
				)
				(justify left bottom)
				(hide yes)
			)
		)
		(property "Public" "False"
			(at 92.71 102.235 0)
			(effects
				(font
					(size 1.27 1.27)
				)
				(justify left bottom)
				(hide yes)
			)
		)
		(pin "1"
		)
		(pin "2"
		)
		(instances
			(project "ddr5-testbed"
				(path ""
					(reference "C15")
					(unit 1)
				)
			)
		)
	)
	(symbol
		(lib_id "antmicropower:GND")
		(at 125.73 86.995 0)
		(unit 1)
		(exclude_from_sim no)
		(in_bom yes)
		(on_board yes)
		(dnp no)
		(fields_autoplaced yes)
		(property "Reference" "#PWR015"
			(at 125.73 93.345 0)
			(effects
				(font
					(size 1.27 1.27)
				)
				(hide yes)
			)
		)
		(property "Value" "GND"
			(at 125.73 91.44 0)
			(effects
				(font
					(size 1.27 1.27)
				)
			)
		)
		(property "Footprint" ""
			(at 125.73 86.995 0)
			(effects
				(font
					(size 1.27 1.27)
				)
				(hide yes)
			)
		)
		(property "Datasheet" ""
			(at 125.73 86.995 0)
			(effects
				(font
					(size 1.27 1.27)
				)
				(hide yes)
			)
		)
		(property "Description" ""
			(at 125.73 86.995 0)
			(effects
				(font
					(size 1.27 1.27)
				)
			)
		)
		(pin "1"
		)
		(instances
			(project "ddr5-testbed"
				(path ""
					(reference "#PWR015")
					(unit 1)
				)
			)
		)
	)
	(symbol
		(lib_id "antmicroCapacitorsmisc:C_100n_0201")
		(at 320.04 81.915 270)
		(unit 1)
		(exclude_from_sim no)
		(in_bom yes)
		(on_board yes)
		(dnp no)
		(fields_autoplaced yes)
		(property "Reference" "C18"
			(at 322.58 83.1913 90)
			(effects
				(font
					(size 1.27 1.27)
				)
				(justify left)
			)
		)
		(property "Value" "C_100n_0201"
			(at 309.88 102.235 0)
			(effects
				(font
					(size 1.27 1.27)
					(thickness 0.15)
				)
				(justify left bottom)
				(hide yes)
			)
		)
		(property "Footprint" "antmicro-footprints:C_0201"
			(at 307.34 102.235 0)
			(effects
				(font
					(size 1.27 1.27)
					(thickness 0.15)
				)
				(justify left bottom)
				(hide yes)
			)
		)
		(property "Datasheet" "https://www.yageo.com/en/Chart/Download/pdf/CC0201KRX6S5BB104"
			(at 304.8 102.235 0)
			(effects
				(font
					(size 1.27 1.27)
					(thickness 0.15)
				)
				(justify left bottom)
				(hide yes)
			)
		)
		(property "Description" ""
			(at 320.04 81.915 0)
			(effects
				(font
					(size 1.27 1.27)
				)
			)
		)
		(property "Manufacturer" "YAGEO"
			(at 299.72 102.235 0)
			(effects
				(font
					(size 1.27 1.27)
					(thickness 0.15)
				)
				(justify left bottom)
				(hide yes)
			)
		)
		(property "MPN" "CC0201KRX6S5BB104"
			(at 302.26 102.235 0)
			(effects
				(font
					(size 1.27 1.27)
					(thickness 0.15)
				)
				(justify left bottom)
				(hide yes)
			)
		)
		(property "Val" "100n"
			(at 322.58 86.3662 90)
			(effects
				(font
					(size 1.27 1.27)
					(thickness 0.15)
				)
				(justify left)
			)
		)
		(property "License" "Apache-2.0"
			(at 297.18 102.235 0)
			(effects
				(font
					(size 1.27 1.27)
					(thickness 0.15)
				)
				(justify left bottom)
				(hide yes)
			)
		)
		(property "Author" "Antmicro"
			(at 294.64 102.235 0)
			(effects
				(font
					(size 1.27 1.27)
					(thickness 0.15)
				)
				(justify left bottom)
				(hide yes)
			)
		)
		(property "Voltage" ""
			(at 292.1 102.235 0)
			(effects
				(font
					(size 1.27 1.27)
				)
				(justify left bottom)
				(hide yes)
			)
		)
		(property "Dielectric" ""
			(at 289.56 102.235 0)
			(effects
				(font
					(size 1.27 1.27)
				)
				(justify left bottom)
				(hide yes)
			)
		)
		(property "Public" "False"
			(at 287.02 102.235 0)
			(effects
				(font
					(size 1.27 1.27)
				)
				(justify left bottom)
				(hide yes)
			)
		)
		(pin "1"
		)
		(pin "2"
		)
		(instances
			(project "ddr5-testbed"
				(path ""
					(reference "C18")
					(unit 1)
				)
			)
		)
	)
	(symbol
		(lib_id "antmicropower:GND")
		(at 320.04 86.995 0)
		(unit 1)
		(exclude_from_sim no)
		(in_bom yes)
		(on_board yes)
		(dnp no)
		(fields_autoplaced yes)
		(property "Reference" "#PWR018"
			(at 320.04 93.345 0)
			(effects
				(font
					(size 1.27 1.27)
				)
				(hide yes)
			)
		)
		(property "Value" "GND"
			(at 320.04 91.44 0)
			(effects
				(font
					(size 1.27 1.27)
				)
			)
		)
		(property "Footprint" ""
			(at 320.04 86.995 0)
			(effects
				(font
					(size 1.27 1.27)
				)
				(hide yes)
			)
		)
		(property "Datasheet" ""
			(at 320.04 86.995 0)
			(effects
				(font
					(size 1.27 1.27)
				)
				(hide yes)
			)
		)
		(property "Description" ""
			(at 320.04 86.995 0)
			(effects
				(font
					(size 1.27 1.27)
				)
			)
		)
		(pin "1"
		)
		(instances
			(project "ddr5-testbed"
				(path ""
					(reference "#PWR018")
					(unit 1)
				)
			)
		)
	)
	(symbol
		(lib_id "antmicroCapacitorsmisc:C_100n_0201")
		(at 80.01 105.41 270)
		(unit 1)
		(exclude_from_sim no)
		(in_bom yes)
		(on_board yes)
		(dnp no)
		(fields_autoplaced yes)
		(property "Reference" "C23"
			(at 82.55 106.6863 90)
			(effects
				(font
					(size 1.27 1.27)
				)
				(justify left)
			)
		)
		(property "Value" "C_100n_0201"
			(at 69.85 125.73 0)
			(effects
				(font
					(size 1.27 1.27)
					(thickness 0.15)
				)
				(justify left bottom)
				(hide yes)
			)
		)
		(property "Footprint" "antmicro-footprints:C_0201"
			(at 67.31 125.73 0)
			(effects
				(font
					(size 1.27 1.27)
					(thickness 0.15)
				)
				(justify left bottom)
				(hide yes)
			)
		)
		(property "Datasheet" "https://www.yageo.com/en/Chart/Download/pdf/CC0201KRX6S5BB104"
			(at 64.77 125.73 0)
			(effects
				(font
					(size 1.27 1.27)
					(thickness 0.15)
				)
				(justify left bottom)
				(hide yes)
			)
		)
		(property "Description" ""
			(at 80.01 105.41 0)
			(effects
				(font
					(size 1.27 1.27)
				)
			)
		)
		(property "Manufacturer" "YAGEO"
			(at 59.69 125.73 0)
			(effects
				(font
					(size 1.27 1.27)
					(thickness 0.15)
				)
				(justify left bottom)
				(hide yes)
			)
		)
		(property "MPN" "CC0201KRX6S5BB104"
			(at 62.23 125.73 0)
			(effects
				(font
					(size 1.27 1.27)
					(thickness 0.15)
				)
				(justify left bottom)
				(hide yes)
			)
		)
		(property "Val" "100n"
			(at 82.55 109.8612 90)
			(effects
				(font
					(size 1.27 1.27)
					(thickness 0.15)
				)
				(justify left)
			)
		)
		(property "License" "Apache-2.0"
			(at 57.15 125.73 0)
			(effects
				(font
					(size 1.27 1.27)
					(thickness 0.15)
				)
				(justify left bottom)
				(hide yes)
			)
		)
		(property "Author" "Antmicro"
			(at 54.61 125.73 0)
			(effects
				(font
					(size 1.27 1.27)
					(thickness 0.15)
				)
				(justify left bottom)
				(hide yes)
			)
		)
		(property "Voltage" ""
			(at 52.07 125.73 0)
			(effects
				(font
					(size 1.27 1.27)
				)
				(justify left bottom)
				(hide yes)
			)
		)
		(property "Dielectric" ""
			(at 49.53 125.73 0)
			(effects
				(font
					(size 1.27 1.27)
				)
				(justify left bottom)
				(hide yes)
			)
		)
		(property "Public" "False"
			(at 46.99 125.73 0)
			(effects
				(font
					(size 1.27 1.27)
				)
				(justify left bottom)
				(hide yes)
			)
		)
		(pin "1"
		)
		(pin "2"
		)
		(instances
			(project "ddr5-testbed"
				(path ""
					(reference "C23")
					(unit 1)
				)
			)
		)
	)
	(symbol
		(lib_id "antmicropower:GND")
		(at 80.01 110.49 0)
		(unit 1)
		(exclude_from_sim no)
		(in_bom yes)
		(on_board yes)
		(dnp no)
		(fields_autoplaced yes)
		(property "Reference" "#PWR024"
			(at 80.01 116.84 0)
			(effects
				(font
					(size 1.27 1.27)
				)
				(hide yes)
			)
		)
		(property "Value" "GND"
			(at 80.01 115.57 0)
			(effects
				(font
					(size 1.27 1.27)
				)
			)
		)
		(property "Footprint" ""
			(at 80.01 110.49 0)
			(effects
				(font
					(size 1.27 1.27)
				)
				(hide yes)
			)
		)
		(property "Datasheet" ""
			(at 80.01 110.49 0)
			(effects
				(font
					(size 1.27 1.27)
				)
				(hide yes)
			)
		)
		(property "Description" ""
			(at 80.01 110.49 0)
			(effects
				(font
					(size 1.27 1.27)
				)
			)
		)
		(pin "1"
		)
		(instances
			(project "ddr5-testbed"
				(path ""
					(reference "#PWR024")
					(unit 1)
				)
			)
		)
	)
	(symbol
		(lib_id "antmicroCapacitorsmisc:C_100n_0201")
		(at 91.44 105.41 270)
		(unit 1)
		(exclude_from_sim no)
		(in_bom yes)
		(on_board yes)
		(dnp no)
		(fields_autoplaced yes)
		(property "Reference" "C26"
			(at 93.98 106.6863 90)
			(effects
				(font
					(size 1.27 1.27)
				)
				(justify left)
			)
		)
		(property "Value" "C_100n_0201"
			(at 81.28 125.73 0)
			(effects
				(font
					(size 1.27 1.27)
					(thickness 0.15)
				)
				(justify left bottom)
				(hide yes)
			)
		)
		(property "Footprint" "antmicro-footprints:C_0201"
			(at 78.74 125.73 0)
			(effects
				(font
					(size 1.27 1.27)
					(thickness 0.15)
				)
				(justify left bottom)
				(hide yes)
			)
		)
		(property "Datasheet" "https://www.yageo.com/en/Chart/Download/pdf/CC0201KRX6S5BB104"
			(at 76.2 125.73 0)
			(effects
				(font
					(size 1.27 1.27)
					(thickness 0.15)
				)
				(justify left bottom)
				(hide yes)
			)
		)
		(property "Description" ""
			(at 91.44 105.41 0)
			(effects
				(font
					(size 1.27 1.27)
				)
			)
		)
		(property "Manufacturer" "YAGEO"
			(at 71.12 125.73 0)
			(effects
				(font
					(size 1.27 1.27)
					(thickness 0.15)
				)
				(justify left bottom)
				(hide yes)
			)
		)
		(property "MPN" "CC0201KRX6S5BB104"
			(at 73.66 125.73 0)
			(effects
				(font
					(size 1.27 1.27)
					(thickness 0.15)
				)
				(justify left bottom)
				(hide yes)
			)
		)
		(property "Val" "100n"
			(at 93.98 109.8612 90)
			(effects
				(font
					(size 1.27 1.27)
					(thickness 0.15)
				)
				(justify left)
			)
		)
		(property "License" "Apache-2.0"
			(at 68.58 125.73 0)
			(effects
				(font
					(size 1.27 1.27)
					(thickness 0.15)
				)
				(justify left bottom)
				(hide yes)
			)
		)
		(property "Author" "Antmicro"
			(at 66.04 125.73 0)
			(effects
				(font
					(size 1.27 1.27)
					(thickness 0.15)
				)
				(justify left bottom)
				(hide yes)
			)
		)
		(property "Voltage" ""
			(at 63.5 125.73 0)
			(effects
				(font
					(size 1.27 1.27)
				)
				(justify left bottom)
				(hide yes)
			)
		)
		(property "Dielectric" ""
			(at 60.96 125.73 0)
			(effects
				(font
					(size 1.27 1.27)
				)
				(justify left bottom)
				(hide yes)
			)
		)
		(property "Public" "False"
			(at 58.42 125.73 0)
			(effects
				(font
					(size 1.27 1.27)
				)
				(justify left bottom)
				(hide yes)
			)
		)
		(pin "1"
		)
		(pin "2"
		)
		(instances
			(project "ddr5-testbed"
				(path ""
					(reference "C26")
					(unit 1)
				)
			)
		)
	)
	(symbol
		(lib_id "antmicropower:GND")
		(at 91.44 110.49 0)
		(unit 1)
		(exclude_from_sim no)
		(in_bom yes)
		(on_board yes)
		(dnp no)
		(fields_autoplaced yes)
		(property "Reference" "#PWR027"
			(at 91.44 116.84 0)
			(effects
				(font
					(size 1.27 1.27)
				)
				(hide yes)
			)
		)
		(property "Value" "GND"
			(at 91.44 115.57 0)
			(effects
				(font
					(size 1.27 1.27)
				)
			)
		)
		(property "Footprint" ""
			(at 91.44 110.49 0)
			(effects
				(font
					(size 1.27 1.27)
				)
				(hide yes)
			)
		)
		(property "Datasheet" ""
			(at 91.44 110.49 0)
			(effects
				(font
					(size 1.27 1.27)
				)
				(hide yes)
			)
		)
		(property "Description" ""
			(at 91.44 110.49 0)
			(effects
				(font
					(size 1.27 1.27)
				)
			)
		)
		(pin "1"
		)
		(instances
			(project "ddr5-testbed"
				(path ""
					(reference "#PWR027")
					(unit 1)
				)
			)
		)
	)
	(symbol
		(lib_id "antmicroCapacitorsmisc:C_100n_0201")
		(at 102.87 105.41 270)
		(unit 1)
		(exclude_from_sim no)
		(in_bom yes)
		(on_board yes)
		(dnp no)
		(fields_autoplaced yes)
		(property "Reference" "C28"
			(at 105.41 106.6863 90)
			(effects
				(font
					(size 1.27 1.27)
				)
				(justify left)
			)
		)
		(property "Value" "C_100n_0201"
			(at 92.71 125.73 0)
			(effects
				(font
					(size 1.27 1.27)
					(thickness 0.15)
				)
				(justify left bottom)
				(hide yes)
			)
		)
		(property "Footprint" "antmicro-footprints:C_0201"
			(at 90.17 125.73 0)
			(effects
				(font
					(size 1.27 1.27)
					(thickness 0.15)
				)
				(justify left bottom)
				(hide yes)
			)
		)
		(property "Datasheet" "https://www.yageo.com/en/Chart/Download/pdf/CC0201KRX6S5BB104"
			(at 87.63 125.73 0)
			(effects
				(font
					(size 1.27 1.27)
					(thickness 0.15)
				)
				(justify left bottom)
				(hide yes)
			)
		)
		(property "Description" ""
			(at 102.87 105.41 0)
			(effects
				(font
					(size 1.27 1.27)
				)
			)
		)
		(property "Manufacturer" "YAGEO"
			(at 82.55 125.73 0)
			(effects
				(font
					(size 1.27 1.27)
					(thickness 0.15)
				)
				(justify left bottom)
				(hide yes)
			)
		)
		(property "MPN" "CC0201KRX6S5BB104"
			(at 85.09 125.73 0)
			(effects
				(font
					(size 1.27 1.27)
					(thickness 0.15)
				)
				(justify left bottom)
				(hide yes)
			)
		)
		(property "Val" "100n"
			(at 105.41 109.8612 90)
			(effects
				(font
					(size 1.27 1.27)
					(thickness 0.15)
				)
				(justify left)
			)
		)
		(property "License" "Apache-2.0"
			(at 80.01 125.73 0)
			(effects
				(font
					(size 1.27 1.27)
					(thickness 0.15)
				)
				(justify left bottom)
				(hide yes)
			)
		)
		(property "Author" "Antmicro"
			(at 77.47 125.73 0)
			(effects
				(font
					(size 1.27 1.27)
					(thickness 0.15)
				)
				(justify left bottom)
				(hide yes)
			)
		)
		(property "Voltage" ""
			(at 74.93 125.73 0)
			(effects
				(font
					(size 1.27 1.27)
				)
				(justify left bottom)
				(hide yes)
			)
		)
		(property "Dielectric" ""
			(at 72.39 125.73 0)
			(effects
				(font
					(size 1.27 1.27)
				)
				(justify left bottom)
				(hide yes)
			)
		)
		(property "Public" "False"
			(at 69.85 125.73 0)
			(effects
				(font
					(size 1.27 1.27)
				)
				(justify left bottom)
				(hide yes)
			)
		)
		(pin "1"
		)
		(pin "2"
		)
		(instances
			(project "ddr5-testbed"
				(path ""
					(reference "C28")
					(unit 1)
				)
			)
		)
	)
	(symbol
		(lib_id "antmicropower:GND")
		(at 102.87 110.49 0)
		(unit 1)
		(exclude_from_sim no)
		(in_bom yes)
		(on_board yes)
		(dnp no)
		(fields_autoplaced yes)
		(property "Reference" "#PWR029"
			(at 102.87 116.84 0)
			(effects
				(font
					(size 1.27 1.27)
				)
				(hide yes)
			)
		)
		(property "Value" "GND"
			(at 102.87 115.57 0)
			(effects
				(font
					(size 1.27 1.27)
				)
			)
		)
		(property "Footprint" ""
			(at 102.87 110.49 0)
			(effects
				(font
					(size 1.27 1.27)
				)
				(hide yes)
			)
		)
		(property "Datasheet" ""
			(at 102.87 110.49 0)
			(effects
				(font
					(size 1.27 1.27)
				)
				(hide yes)
			)
		)
		(property "Description" ""
			(at 102.87 110.49 0)
			(effects
				(font
					(size 1.27 1.27)
				)
			)
		)
		(pin "1"
		)
		(instances
			(project "ddr5-testbed"
				(path ""
					(reference "#PWR029")
					(unit 1)
				)
			)
		)
	)
	(symbol
		(lib_id "antmicroCapacitorsmisc:C_100n_0201")
		(at 114.3 105.41 270)
		(unit 1)
		(exclude_from_sim no)
		(in_bom yes)
		(on_board yes)
		(dnp no)
		(fields_autoplaced yes)
		(property "Reference" "C30"
			(at 117.475 106.6863 90)
			(effects
				(font
					(size 1.27 1.27)
				)
				(justify left)
			)
		)
		(property "Value" "C_100n_0201"
			(at 104.14 125.73 0)
			(effects
				(font
					(size 1.27 1.27)
					(thickness 0.15)
				)
				(justify left bottom)
				(hide yes)
			)
		)
		(property "Footprint" "antmicro-footprints:C_0201"
			(at 101.6 125.73 0)
			(effects
				(font
					(size 1.27 1.27)
					(thickness 0.15)
				)
				(justify left bottom)
				(hide yes)
			)
		)
		(property "Datasheet" "https://www.yageo.com/en/Chart/Download/pdf/CC0201KRX6S5BB104"
			(at 99.06 125.73 0)
			(effects
				(font
					(size 1.27 1.27)
					(thickness 0.15)
				)
				(justify left bottom)
				(hide yes)
			)
		)
		(property "Description" ""
			(at 114.3 105.41 0)
			(effects
				(font
					(size 1.27 1.27)
				)
			)
		)
		(property "Manufacturer" "YAGEO"
			(at 93.98 125.73 0)
			(effects
				(font
					(size 1.27 1.27)
					(thickness 0.15)
				)
				(justify left bottom)
				(hide yes)
			)
		)
		(property "MPN" "CC0201KRX6S5BB104"
			(at 96.52 125.73 0)
			(effects
				(font
					(size 1.27 1.27)
					(thickness 0.15)
				)
				(justify left bottom)
				(hide yes)
			)
		)
		(property "Val" "100n"
			(at 117.475 109.8612 90)
			(effects
				(font
					(size 1.27 1.27)
					(thickness 0.15)
				)
				(justify left)
			)
		)
		(property "License" "Apache-2.0"
			(at 91.44 125.73 0)
			(effects
				(font
					(size 1.27 1.27)
					(thickness 0.15)
				)
				(justify left bottom)
				(hide yes)
			)
		)
		(property "Author" "Antmicro"
			(at 88.9 125.73 0)
			(effects
				(font
					(size 1.27 1.27)
					(thickness 0.15)
				)
				(justify left bottom)
				(hide yes)
			)
		)
		(property "Voltage" ""
			(at 86.36 125.73 0)
			(effects
				(font
					(size 1.27 1.27)
				)
				(justify left bottom)
				(hide yes)
			)
		)
		(property "Dielectric" ""
			(at 83.82 125.73 0)
			(effects
				(font
					(size 1.27 1.27)
				)
				(justify left bottom)
				(hide yes)
			)
		)
		(property "Public" "False"
			(at 81.28 125.73 0)
			(effects
				(font
					(size 1.27 1.27)
				)
				(justify left bottom)
				(hide yes)
			)
		)
		(pin "1"
		)
		(pin "2"
		)
		(instances
			(project "ddr5-testbed"
				(path ""
					(reference "C30")
					(unit 1)
				)
			)
		)
	)
	(symbol
		(lib_id "antmicropower:GND")
		(at 114.3 110.49 0)
		(unit 1)
		(exclude_from_sim no)
		(in_bom yes)
		(on_board yes)
		(dnp no)
		(fields_autoplaced yes)
		(property "Reference" "#PWR031"
			(at 114.3 116.84 0)
			(effects
				(font
					(size 1.27 1.27)
				)
				(hide yes)
			)
		)
		(property "Value" "GND"
			(at 114.3 115.57 0)
			(effects
				(font
					(size 1.27 1.27)
				)
			)
		)
		(property "Footprint" ""
			(at 114.3 110.49 0)
			(effects
				(font
					(size 1.27 1.27)
				)
				(hide yes)
			)
		)
		(property "Datasheet" ""
			(at 114.3 110.49 0)
			(effects
				(font
					(size 1.27 1.27)
				)
				(hide yes)
			)
		)
		(property "Description" ""
			(at 114.3 110.49 0)
			(effects
				(font
					(size 1.27 1.27)
				)
			)
		)
		(pin "1"
		)
		(instances
			(project "ddr5-testbed"
				(path ""
					(reference "#PWR031")
					(unit 1)
				)
			)
		)
	)
	(symbol
		(lib_id "antmicroCapacitorsmisc:C_100n_0201")
		(at 125.73 105.41 270)
		(unit 1)
		(exclude_from_sim no)
		(in_bom yes)
		(on_board yes)
		(dnp no)
		(fields_autoplaced yes)
		(property "Reference" "C32"
			(at 128.27 106.6863 90)
			(effects
				(font
					(size 1.27 1.27)
				)
				(justify left)
			)
		)
		(property "Value" "C_100n_0201"
			(at 115.57 125.73 0)
			(effects
				(font
					(size 1.27 1.27)
					(thickness 0.15)
				)
				(justify left bottom)
				(hide yes)
			)
		)
		(property "Footprint" "antmicro-footprints:C_0201"
			(at 113.03 125.73 0)
			(effects
				(font
					(size 1.27 1.27)
					(thickness 0.15)
				)
				(justify left bottom)
				(hide yes)
			)
		)
		(property "Datasheet" "https://www.yageo.com/en/Chart/Download/pdf/CC0201KRX6S5BB104"
			(at 110.49 125.73 0)
			(effects
				(font
					(size 1.27 1.27)
					(thickness 0.15)
				)
				(justify left bottom)
				(hide yes)
			)
		)
		(property "Description" ""
			(at 125.73 105.41 0)
			(effects
				(font
					(size 1.27 1.27)
				)
			)
		)
		(property "Manufacturer" "YAGEO"
			(at 105.41 125.73 0)
			(effects
				(font
					(size 1.27 1.27)
					(thickness 0.15)
				)
				(justify left bottom)
				(hide yes)
			)
		)
		(property "MPN" "CC0201KRX6S5BB104"
			(at 107.95 125.73 0)
			(effects
				(font
					(size 1.27 1.27)
					(thickness 0.15)
				)
				(justify left bottom)
				(hide yes)
			)
		)
		(property "Val" "100n"
			(at 128.27 109.8612 90)
			(effects
				(font
					(size 1.27 1.27)
					(thickness 0.15)
				)
				(justify left)
			)
		)
		(property "License" "Apache-2.0"
			(at 102.87 125.73 0)
			(effects
				(font
					(size 1.27 1.27)
					(thickness 0.15)
				)
				(justify left bottom)
				(hide yes)
			)
		)
		(property "Author" "Antmicro"
			(at 100.33 125.73 0)
			(effects
				(font
					(size 1.27 1.27)
					(thickness 0.15)
				)
				(justify left bottom)
				(hide yes)
			)
		)
		(property "Voltage" ""
			(at 97.79 125.73 0)
			(effects
				(font
					(size 1.27 1.27)
				)
				(justify left bottom)
				(hide yes)
			)
		)
		(property "Dielectric" ""
			(at 95.25 125.73 0)
			(effects
				(font
					(size 1.27 1.27)
				)
				(justify left bottom)
				(hide yes)
			)
		)
		(property "Public" "False"
			(at 92.71 125.73 0)
			(effects
				(font
					(size 1.27 1.27)
				)
				(justify left bottom)
				(hide yes)
			)
		)
		(pin "1"
		)
		(pin "2"
		)
		(instances
			(project "ddr5-testbed"
				(path ""
					(reference "C32")
					(unit 1)
				)
			)
		)
	)
	(symbol
		(lib_id "antmicropower:GND")
		(at 125.73 110.49 0)
		(unit 1)
		(exclude_from_sim no)
		(in_bom yes)
		(on_board yes)
		(dnp no)
		(fields_autoplaced yes)
		(property "Reference" "#PWR033"
			(at 125.73 116.84 0)
			(effects
				(font
					(size 1.27 1.27)
				)
				(hide yes)
			)
		)
		(property "Value" "GND"
			(at 125.73 115.57 0)
			(effects
				(font
					(size 1.27 1.27)
				)
			)
		)
		(property "Footprint" ""
			(at 125.73 110.49 0)
			(effects
				(font
					(size 1.27 1.27)
				)
				(hide yes)
			)
		)
		(property "Datasheet" ""
			(at 125.73 110.49 0)
			(effects
				(font
					(size 1.27 1.27)
				)
				(hide yes)
			)
		)
		(property "Description" ""
			(at 125.73 110.49 0)
			(effects
				(font
					(size 1.27 1.27)
				)
			)
		)
		(pin "1"
		)
		(instances
			(project "ddr5-testbed"
				(path ""
					(reference "#PWR033")
					(unit 1)
				)
			)
		)
	)
	(symbol
		(lib_id "antmicroResistors0402:R_0R_0402")
		(at 233.045 121.92 0)
		(unit 1)
		(exclude_from_sim no)
		(in_bom yes)
		(on_board yes)
		(dnp no)
		(property "Reference" "R7"
			(at 229.87 120.65 0)
			(effects
				(font
					(size 1.27 1.27)
				)
			)
		)
		(property "Value" "R_0R_0402"
			(at 253.365 134.62 0)
			(effects
				(font
					(size 1.27 1.27)
					(thickness 0.15)
				)
				(justify left bottom)
				(hide yes)
			)
		)
		(property "Footprint" "antmicro-footprints:R_0402_1005Metric"
			(at 253.365 137.16 0)
			(effects
				(font
					(size 1.27 1.27)
					(thickness 0.15)
				)
				(justify left bottom)
				(hide yes)
			)
		)
		(property "Datasheet" "https://industrial.panasonic.com/cdbs/www-data/pdf/RDA0000/AOA0000C301.pdf"
			(at 253.365 139.7 0)
			(effects
				(font
					(size 1.27 1.27)
					(thickness 0.15)
				)
				(justify left bottom)
				(hide yes)
			)
		)
		(property "Description" ""
			(at 233.045 121.92 0)
			(effects
				(font
					(size 1.27 1.27)
				)
			)
		)
		(property "Manufacturer" "Panasonic"
			(at 253.365 144.78 0)
			(effects
				(font
					(size 1.27 1.27)
					(thickness 0.15)
				)
				(justify left bottom)
				(hide yes)
			)
		)
		(property "MPN" "ERJ2GE0R00X"
			(at 253.365 142.24 0)
			(effects
				(font
					(size 1.27 1.27)
					(thickness 0.15)
				)
				(justify left bottom)
				(hide yes)
			)
		)
		(property "Val" "0R"
			(at 239.395 120.65 0)
			(effects
				(font
					(size 1.27 1.27)
					(thickness 0.15)
				)
			)
		)
		(property "License" "Apache-2.0"
			(at 253.365 147.32 0)
			(effects
				(font
					(size 1.27 1.27)
					(thickness 0.15)
				)
				(justify left bottom)
				(hide yes)
			)
		)
		(property "Author" "Antmicro"
			(at 253.365 149.86 0)
			(effects
				(font
					(size 1.27 1.27)
					(thickness 0.15)
				)
				(justify left bottom)
				(hide yes)
			)
		)
		(property "Tolerance" "~"
			(at 253.365 132.08 0)
			(effects
				(font
					(size 1.27 1.27)
				)
				(justify left bottom)
				(hide yes)
			)
		)
		(property "Current" "1A"
			(at 253.365 152.4 0)
			(effects
				(font
					(size 1.27 1.27)
					(thickness 0.15)
				)
				(justify left bottom)
				(hide yes)
			)
		)
		(pin "1"
		)
		(pin "2"
		)
		(instances
			(project "ddr5-testbed"
				(path ""
					(reference "R7")
					(unit 1)
				)
			)
		)
	)
	(symbol
		(lib_id "antmicropower:GND")
		(at 161.925 189.23 0)
		(mirror y)
		(unit 1)
		(exclude_from_sim no)
		(in_bom yes)
		(on_board yes)
		(dnp no)
		(fields_autoplaced yes)
		(property "Reference" "#PWR0105"
			(at 161.925 195.58 0)
			(effects
				(font
					(size 1.27 1.27)
				)
				(hide yes)
			)
		)
		(property "Value" "GND"
			(at 161.925 193.675 0)
			(effects
				(font
					(size 1.27 1.27)
				)
			)
		)
		(property "Footprint" ""
			(at 161.925 189.23 0)
			(effects
				(font
					(size 1.27 1.27)
				)
				(hide yes)
			)
		)
		(property "Datasheet" ""
			(at 161.925 189.23 0)
			(effects
				(font
					(size 1.27 1.27)
				)
				(hide yes)
			)
		)
		(property "Description" ""
			(at 161.925 189.23 0)
			(effects
				(font
					(size 1.27 1.27)
				)
			)
		)
		(pin "1"
		)
		(instances
			(project "ddr5-testbed"
				(path ""
					(reference "#PWR0105")
					(unit 1)
				)
			)
		)
	)
	(symbol
		(lib_id "antmicroFerriteBeadsandChips:FB_220Z_1.5A_WE-CBF_0805")
		(at 97.79 68.58 0)
		(unit 1)
		(exclude_from_sim no)
		(in_bom yes)
		(on_board yes)
		(dnp no)
		(property "Reference" "FB1"
			(at 100.33 62.23 0)
			(effects
				(font
					(size 1.27 1.27)
				)
			)
		)
		(property "Value" "FB_220Z_1.5A_WE-CBF_0805"
			(at 100.2919 62.23 0)
			(effects
				(font
					(size 1.27 1.27)
					(thickness 0.15)
				)
				(hide yes)
			)
		)
		(property "Footprint" "antmicro-footprints:FB_0805_2012Metric"
			(at 113.03 76.2 0)
			(effects
				(font
					(size 1.27 1.27)
					(thickness 0.15)
				)
				(justify left bottom)
				(hide yes)
			)
		)
		(property "Datasheet" "https://www.we-online.com/katalog/datasheet/742792022.pdf"
			(at 113.03 78.74 0)
			(effects
				(font
					(size 1.27 1.27)
					(thickness 0.15)
				)
				(justify left bottom)
				(hide yes)
			)
		)
		(property "Description" ""
			(at 97.79 68.58 0)
			(effects
				(font
					(size 1.27 1.27)
				)
			)
		)
		(property "MPN" "742792022"
			(at 113.03 83.82 0)
			(effects
				(font
					(size 1.27 1.27)
					(thickness 0.15)
				)
				(justify left bottom)
				(hide yes)
			)
		)
		(property "Manufacturer" "Würth Elektronik"
			(at 113.03 86.36 0)
			(effects
				(font
					(size 1.27 1.27)
					(thickness 0.15)
				)
				(justify left bottom)
				(hide yes)
			)
		)
		(property "Val" "220Z/1.5A"
			(at 100.2919 64.77 0)
			(effects
				(font
					(size 1.27 1.27)
					(thickness 0.15)
				)
			)
		)
		(property "Current" "1.5A"
			(at 113.03 81.28 0)
			(effects
				(font
					(size 1.27 1.27)
					(thickness 0.15)
				)
				(justify left bottom)
				(hide yes)
			)
		)
		(property "Author" "Antmicro"
			(at 113.03 88.9 0)
			(effects
				(font
					(size 1.27 1.27)
					(thickness 0.15)
				)
				(justify left bottom)
				(hide yes)
			)
		)
		(property "License" "Apache-2.0"
			(at 113.03 91.44 0)
			(effects
				(font
					(size 1.27 1.27)
					(thickness 0.15)
				)
				(justify left bottom)
				(hide yes)
			)
		)
		(property "Public" "False"
			(at 118.11 83.82 0)
			(effects
				(font
					(size 1.27 1.27)
				)
				(justify left bottom)
				(hide yes)
			)
		)
		(pin "1"
		)
		(pin "2"
		)
		(instances
			(project "ddr5-testbed"
				(path ""
					(reference "FB1")
					(unit 1)
				)
			)
		)
	)
	(symbol
		(lib_id "antmicroMemory:MT60B2G8HB-48B_A")
		(at 170.815 121.92 0)
		(unit 1)
		(exclude_from_sim no)
		(in_bom yes)
		(on_board yes)
		(dnp no)
		(fields_autoplaced yes)
		(property "Reference" "U1"
			(at 189.865 114.3 0)
			(effects
				(font
					(size 1.27 1.27)
				)
			)
		)
		(property "Value" "MT60B2G8HB-48B_A"
			(at 222.885 130.81 0)
			(effects
				(font
					(size 1.27 1.27)
					(thickness 0.15)
				)
				(justify left bottom)
				(hide yes)
			)
		)
		(property "Footprint" "antmicro-footprints:BGA-82_11x9mm_Layout13x11_P0.8mm_DDR5_MO-210-AN"
			(at 222.885 133.35 0)
			(effects
				(font
					(size 1.27 1.27)
					(thickness 0.15)
				)
				(justify left bottom)
				(hide yes)
			)
		)
		(property "Datasheet" "https://www.farnell.com/datasheets/3704816.pdf"
			(at 222.885 135.89 0)
			(effects
				(font
					(size 1.27 1.27)
					(thickness 0.15)
				)
				(justify left bottom)
				(hide yes)
			)
		)
		(property "Description" ""
			(at 170.815 121.92 0)
			(effects
				(font
					(size 1.27 1.27)
				)
			)
		)
		(property "Manufacturer" "Micron Technology"
			(at 222.885 138.43 0)
			(effects
				(font
					(size 1.27 1.27)
					(thickness 0.15)
				)
				(justify left bottom)
				(hide yes)
			)
		)
		(property "MPN" "MT60B2G8HB-48B:A"
			(at 189.865 116.84 0)
			(effects
				(font
					(size 1.27 1.27)
					(thickness 0.15)
				)
			)
		)
		(property "Author" "Antmicro"
			(at 222.885 143.51 0)
			(effects
				(font
					(size 1.27 1.27)
					(thickness 0.15)
				)
				(justify left bottom)
				(hide yes)
			)
		)
		(property "License" "Apache-2.0"
			(at 222.885 146.05 0)
			(effects
				(font
					(size 1.27 1.27)
					(thickness 0.15)
				)
				(justify left bottom)
				(hide yes)
			)
		)
		(pin "A1"
		)
		(pin "A10"
		)
		(pin "A11"
		)
		(pin "A2"
		)
		(pin "A3"
		)
		(pin "A4"
		)
		(pin "A8"
		)
		(pin "A9"
		)
		(pin "B10"
		)
		(pin "B2"
		)
		(pin "B3"
		)
		(pin "B4"
		)
		(pin "B8"
		)
		(pin "B9"
		)
		(pin "C10"
		)
		(pin "C2"
		)
		(pin "C3"
		)
		(pin "C4"
		)
		(pin "C8"
		)
		(pin "C9"
		)
		(pin "D10"
		)
		(pin "D2"
		)
		(pin "D3"
		)
		(pin "D4"
		)
		(pin "D8"
		)
		(pin "D9"
		)
		(pin "E10"
		)
		(pin "E2"
		)
		(pin "E3"
		)
		(pin "E4"
		)
		(pin "E8"
		)
		(pin "E9"
		)
		(pin "F10"
		)
		(pin "F2"
		)
		(pin "F3"
		)
		(pin "F4"
		)
		(pin "F8"
		)
		(pin "F9"
		)
		(pin "G10"
		)
		(pin "G2"
		)
		(pin "G3"
		)
		(pin "G4"
		)
		(pin "G8"
		)
		(pin "G9"
		)
		(pin "H10"
		)
		(pin "H2"
		)
		(pin "H3"
		)
		(pin "H4"
		)
		(pin "H8"
		)
		(pin "H9"
		)
		(pin "J10"
		)
		(pin "J2"
		)
		(pin "J3"
		)
		(pin "J4"
		)
		(pin "J8"
		)
		(pin "J9"
		)
		(pin "K10"
		)
		(pin "K2"
		)
		(pin "K3"
		)
		(pin "K4"
		)
		(pin "K8"
		)
		(pin "K9"
		)
		(pin "L10"
		)
		(pin "L2"
		)
		(pin "L3"
		)
		(pin "L4"
		)
		(pin "L8"
		)
		(pin "L9"
		)
		(pin "M10"
		)
		(pin "M2"
		)
		(pin "M3"
		)
		(pin "M4"
		)
		(pin "M8"
		)
		(pin "M9"
		)
		(pin "N1"
		)
		(pin "N10"
		)
		(pin "N11"
		)
		(pin "N2"
		)
		(pin "N3"
		)
		(pin "N4"
		)
		(pin "N8"
		)
		(pin "N9"
		)
		(instances
			(project "ddr5-testbed"
				(path ""
					(reference "U1")
					(unit 1)
				)
			)
		)
	)
	(symbol
		(lib_id "antmicroFerriteBeadsandChips:FB_220Z_1.5A_WE-CBF_0805")
		(at 184.785 68.58 0)
		(unit 1)
		(exclude_from_sim no)
		(in_bom yes)
		(on_board yes)
		(dnp no)
		(property "Reference" "FB2"
			(at 187.325 62.23 0)
			(effects
				(font
					(size 1.27 1.27)
				)
			)
		)
		(property "Value" "FB_220Z_1.5A_WE-CBF_0805"
			(at 187.2869 62.23 0)
			(effects
				(font
					(size 1.27 1.27)
					(thickness 0.15)
				)
				(hide yes)
			)
		)
		(property "Footprint" "antmicro-footprints:FB_0805_2012Metric"
			(at 200.025 76.2 0)
			(effects
				(font
					(size 1.27 1.27)
					(thickness 0.15)
				)
				(justify left bottom)
				(hide yes)
			)
		)
		(property "Datasheet" "https://www.we-online.com/katalog/datasheet/742792022.pdf"
			(at 200.025 78.74 0)
			(effects
				(font
					(size 1.27 1.27)
					(thickness 0.15)
				)
				(justify left bottom)
				(hide yes)
			)
		)
		(property "Description" ""
			(at 184.785 68.58 0)
			(effects
				(font
					(size 1.27 1.27)
				)
			)
		)
		(property "MPN" "742792022"
			(at 200.025 83.82 0)
			(effects
				(font
					(size 1.27 1.27)
					(thickness 0.15)
				)
				(justify left bottom)
				(hide yes)
			)
		)
		(property "Manufacturer" "Würth Elektronik"
			(at 200.025 86.36 0)
			(effects
				(font
					(size 1.27 1.27)
					(thickness 0.15)
				)
				(justify left bottom)
				(hide yes)
			)
		)
		(property "Val" "220Z/1.5A"
			(at 187.2869 64.77 0)
			(effects
				(font
					(size 1.27 1.27)
					(thickness 0.15)
				)
			)
		)
		(property "Current" "1.5A"
			(at 200.025 81.28 0)
			(effects
				(font
					(size 1.27 1.27)
					(thickness 0.15)
				)
				(justify left bottom)
				(hide yes)
			)
		)
		(property "Author" "Antmicro"
			(at 200.025 88.9 0)
			(effects
				(font
					(size 1.27 1.27)
					(thickness 0.15)
				)
				(justify left bottom)
				(hide yes)
			)
		)
		(property "License" "Apache-2.0"
			(at 200.025 91.44 0)
			(effects
				(font
					(size 1.27 1.27)
					(thickness 0.15)
				)
				(justify left bottom)
				(hide yes)
			)
		)
		(property "Public" "False"
			(at 205.105 83.82 0)
			(effects
				(font
					(size 1.27 1.27)
				)
				(justify left bottom)
				(hide yes)
			)
		)
		(pin "1"
		)
		(pin "2"
		)
		(instances
			(project "ddr5-testbed"
				(path ""
					(reference "FB2")
					(unit 1)
				)
			)
		)
	)
	(symbol
		(lib_id "antmicroFerriteBeadsandChips:FB_220Z_1.5A_WE-CBF_0805")
		(at 284.48 68.58 0)
		(unit 1)
		(exclude_from_sim no)
		(in_bom yes)
		(on_board yes)
		(dnp no)
		(property "Reference" "FB3"
			(at 287.02 62.23 0)
			(effects
				(font
					(size 1.27 1.27)
				)
			)
		)
		(property "Value" "FB_220Z_1.5A_WE-CBF_0805"
			(at 286.9819 62.23 0)
			(effects
				(font
					(size 1.27 1.27)
					(thickness 0.15)
				)
				(hide yes)
			)
		)
		(property "Footprint" "antmicro-footprints:FB_0805_2012Metric"
			(at 299.72 76.2 0)
			(effects
				(font
					(size 1.27 1.27)
					(thickness 0.15)
				)
				(justify left bottom)
				(hide yes)
			)
		)
		(property "Datasheet" "https://www.we-online.com/katalog/datasheet/742792022.pdf"
			(at 299.72 78.74 0)
			(effects
				(font
					(size 1.27 1.27)
					(thickness 0.15)
				)
				(justify left bottom)
				(hide yes)
			)
		)
		(property "Description" ""
			(at 284.48 68.58 0)
			(effects
				(font
					(size 1.27 1.27)
				)
			)
		)
		(property "MPN" "742792022"
			(at 299.72 83.82 0)
			(effects
				(font
					(size 1.27 1.27)
					(thickness 0.15)
				)
				(justify left bottom)
				(hide yes)
			)
		)
		(property "Manufacturer" "Würth Elektronik"
			(at 299.72 86.36 0)
			(effects
				(font
					(size 1.27 1.27)
					(thickness 0.15)
				)
				(justify left bottom)
				(hide yes)
			)
		)
		(property "Val" "220Z/1.5A"
			(at 286.9819 64.77 0)
			(effects
				(font
					(size 1.27 1.27)
					(thickness 0.15)
				)
			)
		)
		(property "Current" "1.5A"
			(at 299.72 81.28 0)
			(effects
				(font
					(size 1.27 1.27)
					(thickness 0.15)
				)
				(justify left bottom)
				(hide yes)
			)
		)
		(property "Author" "Antmicro"
			(at 299.72 88.9 0)
			(effects
				(font
					(size 1.27 1.27)
					(thickness 0.15)
				)
				(justify left bottom)
				(hide yes)
			)
		)
		(property "License" "Apache-2.0"
			(at 299.72 91.44 0)
			(effects
				(font
					(size 1.27 1.27)
					(thickness 0.15)
				)
				(justify left bottom)
				(hide yes)
			)
		)
		(property "Public" "False"
			(at 304.8 83.82 0)
			(effects
				(font
					(size 1.27 1.27)
				)
				(justify left bottom)
				(hide yes)
			)
		)
		(pin "1"
		)
		(pin "2"
		)
		(instances
			(project "ddr5-testbed"
				(path ""
					(reference "FB3")
					(unit 1)
				)
			)
		)
	)
	(symbol
		(lib_id "antmicropower:GND")
		(at 210.82 189.23 0)
		(mirror y)
		(unit 1)
		(exclude_from_sim no)
		(in_bom yes)
		(on_board yes)
		(dnp no)
		(fields_autoplaced yes)
		(property "Reference" "#PWR0118"
			(at 210.82 195.58 0)
			(effects
				(font
					(size 1.27 1.27)
				)
				(hide yes)
			)
		)
		(property "Value" "GND"
			(at 210.82 193.675 0)
			(effects
				(font
					(size 1.27 1.27)
				)
			)
		)
		(property "Footprint" ""
			(at 210.82 189.23 0)
			(effects
				(font
					(size 1.27 1.27)
				)
				(hide yes)
			)
		)
		(property "Datasheet" ""
			(at 210.82 189.23 0)
			(effects
				(font
					(size 1.27 1.27)
				)
				(hide yes)
			)
		)
		(property "Description" ""
			(at 210.82 189.23 0)
			(effects
				(font
					(size 1.27 1.27)
				)
			)
		)
		(pin "1"
		)
		(instances
			(project "ddr5-testbed"
				(path ""
					(reference "#PWR0118")
					(unit 1)
				)
			)
		)
	)
	(symbol
		(lib_id "antmicroResistors0402:R_1k_0402")
		(at 224.155 109.855 270)
		(unit 1)
		(exclude_from_sim no)
		(in_bom yes)
		(on_board yes)
		(dnp no)
		(fields_autoplaced yes)
		(property "Reference" "R1"
			(at 221.615 111.125 90)
			(effects
				(font
					(size 1.27 1.27)
				)
				(justify right)
			)
		)
		(property "Value" "R_1k_0402"
			(at 211.455 130.175 0)
			(effects
				(font
					(size 1.27 1.27)
					(thickness 0.15)
				)
				(justify left bottom)
				(hide yes)
			)
		)
		(property "Footprint" "antmicro-footprints:R_0402_1005Metric"
			(at 208.915 130.175 0)
			(effects
				(font
					(size 1.27 1.27)
					(thickness 0.15)
				)
				(justify left bottom)
				(hide yes)
			)
		)
		(property "Datasheet" "https://www.bourns.com/docs/product-datasheets/cr.pdf"
			(at 206.375 130.175 0)
			(effects
				(font
					(size 1.27 1.27)
					(thickness 0.15)
				)
				(justify left bottom)
				(hide yes)
			)
		)
		(property "Description" ""
			(at 224.155 109.855 0)
			(effects
				(font
					(size 1.27 1.27)
				)
			)
		)
		(property "Manufacturer" "Bourns"
			(at 201.295 130.175 0)
			(effects
				(font
					(size 1.27 1.27)
					(thickness 0.15)
				)
				(justify left bottom)
				(hide yes)
			)
		)
		(property "MPN" "CR0402-FX-1001GLF"
			(at 203.835 130.175 0)
			(effects
				(font
					(size 1.27 1.27)
					(thickness 0.15)
				)
				(justify left bottom)
				(hide yes)
			)
		)
		(property "Val" "1k"
			(at 221.615 114.2999 90)
			(effects
				(font
					(size 1.27 1.27)
					(thickness 0.15)
				)
				(justify right)
			)
		)
		(property "License" "Apache-2.0"
			(at 198.755 130.175 0)
			(effects
				(font
					(size 1.27 1.27)
					(thickness 0.15)
				)
				(justify left bottom)
				(hide yes)
			)
		)
		(property "Author" "Antmicro"
			(at 196.215 130.175 0)
			(effects
				(font
					(size 1.27 1.27)
					(thickness 0.15)
				)
				(justify left bottom)
				(hide yes)
			)
		)
		(property "Tolerance" "1%"
			(at 213.995 130.175 0)
			(effects
				(font
					(size 1.27 1.27)
				)
				(justify left bottom)
				(hide yes)
			)
		)
		(pin "1"
		)
		(pin "2"
		)
		(instances
			(project "ddr5-testbed"
				(path ""
					(reference "R1")
					(unit 1)
				)
			)
		)
	)
	(symbol
		(lib_id "antmicroResistors0402:R_1k_0402")
		(at 226.695 109.855 270)
		(unit 1)
		(exclude_from_sim no)
		(in_bom yes)
		(on_board yes)
		(dnp no)
		(fields_autoplaced yes)
		(property "Reference" "R5"
			(at 229.235 111.125 90)
			(effects
				(font
					(size 1.27 1.27)
				)
				(justify left)
			)
		)
		(property "Value" "R_1k_0402"
			(at 213.995 130.175 0)
			(effects
				(font
					(size 1.27 1.27)
					(thickness 0.15)
				)
				(justify left bottom)
				(hide yes)
			)
		)
		(property "Footprint" "antmicro-footprints:R_0402_1005Metric"
			(at 211.455 130.175 0)
			(effects
				(font
					(size 1.27 1.27)
					(thickness 0.15)
				)
				(justify left bottom)
				(hide yes)
			)
		)
		(property "Datasheet" "https://www.bourns.com/docs/product-datasheets/cr.pdf"
			(at 208.915 130.175 0)
			(effects
				(font
					(size 1.27 1.27)
					(thickness 0.15)
				)
				(justify left bottom)
				(hide yes)
			)
		)
		(property "Description" ""
			(at 226.695 109.855 0)
			(effects
				(font
					(size 1.27 1.27)
				)
			)
		)
		(property "Manufacturer" "Bourns"
			(at 203.835 130.175 0)
			(effects
				(font
					(size 1.27 1.27)
					(thickness 0.15)
				)
				(justify left bottom)
				(hide yes)
			)
		)
		(property "MPN" "CR0402-FX-1001GLF"
			(at 206.375 130.175 0)
			(effects
				(font
					(size 1.27 1.27)
					(thickness 0.15)
				)
				(justify left bottom)
				(hide yes)
			)
		)
		(property "Val" "1k"
			(at 229.235 114.2999 90)
			(effects
				(font
					(size 1.27 1.27)
					(thickness 0.15)
				)
				(justify left)
			)
		)
		(property "License" "Apache-2.0"
			(at 201.295 130.175 0)
			(effects
				(font
					(size 1.27 1.27)
					(thickness 0.15)
				)
				(justify left bottom)
				(hide yes)
			)
		)
		(property "Author" "Antmicro"
			(at 198.755 130.175 0)
			(effects
				(font
					(size 1.27 1.27)
					(thickness 0.15)
				)
				(justify left bottom)
				(hide yes)
			)
		)
		(property "Tolerance" "1%"
			(at 216.535 130.175 0)
			(effects
				(font
					(size 1.27 1.27)
				)
				(justify left bottom)
				(hide yes)
			)
		)
		(pin "1"
		)
		(pin "2"
		)
		(instances
			(project "ddr5-testbed"
				(path ""
					(reference "R5")
					(unit 1)
				)
			)
		)
	)
	(symbol
		(lib_id "antmicroResistors0402:R_240R_0402")
		(at 161.925 184.15 270)
		(unit 1)
		(exclude_from_sim no)
		(in_bom yes)
		(on_board yes)
		(dnp no)
		(fields_autoplaced yes)
		(property "Reference" "R6"
			(at 163.83 185.42 90)
			(effects
				(font
					(size 1.27 1.27)
				)
				(justify left)
			)
		)
		(property "Value" "R_240R_0402"
			(at 149.225 204.47 0)
			(effects
				(font
					(size 1.27 1.27)
					(thickness 0.15)
				)
				(justify left bottom)
				(hide yes)
			)
		)
		(property "Footprint" "antmicro-footprints:R_0402_1005Metric"
			(at 146.685 204.47 0)
			(effects
				(font
					(size 1.27 1.27)
					(thickness 0.15)
				)
				(justify left bottom)
				(hide yes)
			)
		)
		(property "Datasheet" "https://www.bourns.com/docs/product-datasheets/cr.pdf"
			(at 144.145 204.47 0)
			(effects
				(font
					(size 1.27 1.27)
					(thickness 0.15)
				)
				(justify left bottom)
				(hide yes)
			)
		)
		(property "Description" ""
			(at 161.925 184.15 0)
			(effects
				(font
					(size 1.27 1.27)
				)
			)
		)
		(property "Manufacturer" "Bourns"
			(at 139.065 204.47 0)
			(effects
				(font
					(size 1.27 1.27)
					(thickness 0.15)
				)
				(justify left bottom)
				(hide yes)
			)
		)
		(property "MPN" "CR0402-FX-2400GLF"
			(at 141.605 204.47 0)
			(effects
				(font
					(size 1.27 1.27)
					(thickness 0.15)
				)
				(justify left bottom)
				(hide yes)
			)
		)
		(property "Val" "240R"
			(at 163.83 188.5949 90)
			(effects
				(font
					(size 1.27 1.27)
					(thickness 0.15)
				)
				(justify left)
			)
		)
		(property "License" "Apache-2.0"
			(at 136.525 204.47 0)
			(effects
				(font
					(size 1.27 1.27)
					(thickness 0.15)
				)
				(justify left bottom)
				(hide yes)
			)
		)
		(property "Author" "Antmicro"
			(at 133.985 204.47 0)
			(effects
				(font
					(size 1.27 1.27)
					(thickness 0.15)
				)
				(justify left bottom)
				(hide yes)
			)
		)
		(property "Tolerance" "1%"
			(at 151.765 204.47 0)
			(effects
				(font
					(size 1.27 1.27)
				)
				(justify left bottom)
				(hide yes)
			)
		)
		(pin "1"
		)
		(pin "2"
		)
		(instances
			(project "ddr5-testbed"
				(path ""
					(reference "R6")
					(unit 1)
				)
			)
		)
	)
	(symbol
		(lib_id "antmicroResistors0402:R_0R_0402")
		(at 231.775 180.34 0)
		(unit 1)
		(exclude_from_sim no)
		(in_bom yes)
		(on_board yes)
		(dnp no)
		(property "Reference" "R19"
			(at 229.235 179.07 0)
			(effects
				(font
					(size 1.27 1.27)
				)
			)
		)
		(property "Value" "R_0R_0402"
			(at 252.095 193.04 0)
			(effects
				(font
					(size 1.27 1.27)
					(thickness 0.15)
				)
				(justify left bottom)
				(hide yes)
			)
		)
		(property "Footprint" "antmicro-footprints:R_0402_1005Metric"
			(at 252.095 195.58 0)
			(effects
				(font
					(size 1.27 1.27)
					(thickness 0.15)
				)
				(justify left bottom)
				(hide yes)
			)
		)
		(property "Datasheet" "https://industrial.panasonic.com/cdbs/www-data/pdf/RDA0000/AOA0000C301.pdf"
			(at 252.095 198.12 0)
			(effects
				(font
					(size 1.27 1.27)
					(thickness 0.15)
				)
				(justify left bottom)
				(hide yes)
			)
		)
		(property "Description" ""
			(at 231.775 180.34 0)
			(effects
				(font
					(size 1.27 1.27)
				)
			)
		)
		(property "Manufacturer" "Panasonic"
			(at 252.095 203.2 0)
			(effects
				(font
					(size 1.27 1.27)
					(thickness 0.15)
				)
				(justify left bottom)
				(hide yes)
			)
		)
		(property "MPN" "ERJ2GE0R00X"
			(at 252.095 200.66 0)
			(effects
				(font
					(size 1.27 1.27)
					(thickness 0.15)
				)
				(justify left bottom)
				(hide yes)
			)
		)
		(property "Val" "0R"
			(at 238.125 179.07 0)
			(effects
				(font
					(size 1.27 1.27)
					(thickness 0.15)
				)
			)
		)
		(property "License" "Apache-2.0"
			(at 252.095 205.74 0)
			(effects
				(font
					(size 1.27 1.27)
					(thickness 0.15)
				)
				(justify left bottom)
				(hide yes)
			)
		)
		(property "Author" "Antmicro"
			(at 252.095 208.28 0)
			(effects
				(font
					(size 1.27 1.27)
					(thickness 0.15)
				)
				(justify left bottom)
				(hide yes)
			)
		)
		(property "Tolerance" "~"
			(at 252.095 190.5 0)
			(effects
				(font
					(size 1.27 1.27)
				)
				(justify left bottom)
				(hide yes)
			)
		)
		(property "Current" "1A"
			(at 252.095 210.82 0)
			(effects
				(font
					(size 1.27 1.27)
					(thickness 0.15)
				)
				(justify left bottom)
				(hide yes)
			)
		)
		(pin "1"
		)
		(pin "2"
		)
		(instances
			(project "ddr5-testbed"
				(path ""
					(reference "R19")
					(unit 1)
				)
			)
		)
	)
	(symbol
		(lib_id "antmicroResistors0402:R_0R_0402")
		(at 231.775 177.8 0)
		(unit 1)
		(exclude_from_sim no)
		(in_bom yes)
		(on_board yes)
		(dnp no)
		(property "Reference" "R18"
			(at 229.235 176.53 0)
			(effects
				(font
					(size 1.27 1.27)
				)
			)
		)
		(property "Value" "R_0R_0402"
			(at 252.095 190.5 0)
			(effects
				(font
					(size 1.27 1.27)
					(thickness 0.15)
				)
				(justify left bottom)
				(hide yes)
			)
		)
		(property "Footprint" "antmicro-footprints:R_0402_1005Metric"
			(at 252.095 193.04 0)
			(effects
				(font
					(size 1.27 1.27)
					(thickness 0.15)
				)
				(justify left bottom)
				(hide yes)
			)
		)
		(property "Datasheet" "https://industrial.panasonic.com/cdbs/www-data/pdf/RDA0000/AOA0000C301.pdf"
			(at 252.095 195.58 0)
			(effects
				(font
					(size 1.27 1.27)
					(thickness 0.15)
				)
				(justify left bottom)
				(hide yes)
			)
		)
		(property "Description" ""
			(at 231.775 177.8 0)
			(effects
				(font
					(size 1.27 1.27)
				)
			)
		)
		(property "Manufacturer" "Panasonic"
			(at 252.095 200.66 0)
			(effects
				(font
					(size 1.27 1.27)
					(thickness 0.15)
				)
				(justify left bottom)
				(hide yes)
			)
		)
		(property "MPN" "ERJ2GE0R00X"
			(at 252.095 198.12 0)
			(effects
				(font
					(size 1.27 1.27)
					(thickness 0.15)
				)
				(justify left bottom)
				(hide yes)
			)
		)
		(property "Val" "0R"
			(at 238.125 176.53 0)
			(effects
				(font
					(size 1.27 1.27)
					(thickness 0.15)
				)
			)
		)
		(property "License" "Apache-2.0"
			(at 252.095 203.2 0)
			(effects
				(font
					(size 1.27 1.27)
					(thickness 0.15)
				)
				(justify left bottom)
				(hide yes)
			)
		)
		(property "Author" "Antmicro"
			(at 252.095 205.74 0)
			(effects
				(font
					(size 1.27 1.27)
					(thickness 0.15)
				)
				(justify left bottom)
				(hide yes)
			)
		)
		(property "Tolerance" "~"
			(at 252.095 187.96 0)
			(effects
				(font
					(size 1.27 1.27)
				)
				(justify left bottom)
				(hide yes)
			)
		)
		(property "Current" "1A"
			(at 252.095 208.28 0)
			(effects
				(font
					(size 1.27 1.27)
					(thickness 0.15)
				)
				(justify left bottom)
				(hide yes)
			)
		)
		(pin "1"
		)
		(pin "2"
		)
		(instances
			(project "ddr5-testbed"
				(path ""
					(reference "R18")
					(unit 1)
				)
			)
		)
	)
	(symbol
		(lib_id "antmicroResistors0402:R_0R_0402")
		(at 233.045 134.62 0)
		(unit 1)
		(exclude_from_sim no)
		(in_bom yes)
		(on_board yes)
		(dnp no)
		(property "Reference" "R17"
			(at 230.505 133.35 0)
			(effects
				(font
					(size 1.27 1.27)
				)
			)
		)
		(property "Value" "R_0R_0402"
			(at 253.365 147.32 0)
			(effects
				(font
					(size 1.27 1.27)
					(thickness 0.15)
				)
				(justify left bottom)
				(hide yes)
			)
		)
		(property "Footprint" "antmicro-footprints:R_0402_1005Metric"
			(at 253.365 149.86 0)
			(effects
				(font
					(size 1.27 1.27)
					(thickness 0.15)
				)
				(justify left bottom)
				(hide yes)
			)
		)
		(property "Datasheet" "https://industrial.panasonic.com/cdbs/www-data/pdf/RDA0000/AOA0000C301.pdf"
			(at 253.365 152.4 0)
			(effects
				(font
					(size 1.27 1.27)
					(thickness 0.15)
				)
				(justify left bottom)
				(hide yes)
			)
		)
		(property "Description" ""
			(at 233.045 134.62 0)
			(effects
				(font
					(size 1.27 1.27)
				)
			)
		)
		(property "Manufacturer" "Panasonic"
			(at 253.365 157.48 0)
			(effects
				(font
					(size 1.27 1.27)
					(thickness 0.15)
				)
				(justify left bottom)
				(hide yes)
			)
		)
		(property "MPN" "ERJ2GE0R00X"
			(at 253.365 154.94 0)
			(effects
				(font
					(size 1.27 1.27)
					(thickness 0.15)
				)
				(justify left bottom)
				(hide yes)
			)
		)
		(property "Val" "0R"
			(at 239.395 133.35 0)
			(effects
				(font
					(size 1.27 1.27)
					(thickness 0.15)
				)
			)
		)
		(property "License" "Apache-2.0"
			(at 253.365 160.02 0)
			(effects
				(font
					(size 1.27 1.27)
					(thickness 0.15)
				)
				(justify left bottom)
				(hide yes)
			)
		)
		(property "Author" "Antmicro"
			(at 253.365 162.56 0)
			(effects
				(font
					(size 1.27 1.27)
					(thickness 0.15)
				)
				(justify left bottom)
				(hide yes)
			)
		)
		(property "Tolerance" "~"
			(at 253.365 144.78 0)
			(effects
				(font
					(size 1.27 1.27)
				)
				(justify left bottom)
				(hide yes)
			)
		)
		(property "Current" "1A"
			(at 253.365 165.1 0)
			(effects
				(font
					(size 1.27 1.27)
					(thickness 0.15)
				)
				(justify left bottom)
				(hide yes)
			)
		)
		(pin "1"
		)
		(pin "2"
		)
		(instances
			(project "ddr5-testbed"
				(path ""
					(reference "R17")
					(unit 1)
				)
			)
		)
	)
	(symbol
		(lib_id "antmicroResistors0402:R_0R_0402")
		(at 233.045 127 0)
		(unit 1)
		(exclude_from_sim no)
		(in_bom yes)
		(on_board yes)
		(dnp no)
		(property "Reference" "R4"
			(at 229.87 125.73 0)
			(effects
				(font
					(size 1.27 1.27)
				)
			)
		)
		(property "Value" "R_0R_0402"
			(at 253.365 139.7 0)
			(effects
				(font
					(size 1.27 1.27)
					(thickness 0.15)
				)
				(justify left bottom)
				(hide yes)
			)
		)
		(property "Footprint" "antmicro-footprints:R_0402_1005Metric"
			(at 253.365 142.24 0)
			(effects
				(font
					(size 1.27 1.27)
					(thickness 0.15)
				)
				(justify left bottom)
				(hide yes)
			)
		)
		(property "Datasheet" "https://industrial.panasonic.com/cdbs/www-data/pdf/RDA0000/AOA0000C301.pdf"
			(at 253.365 144.78 0)
			(effects
				(font
					(size 1.27 1.27)
					(thickness 0.15)
				)
				(justify left bottom)
				(hide yes)
			)
		)
		(property "Description" ""
			(at 233.045 127 0)
			(effects
				(font
					(size 1.27 1.27)
				)
			)
		)
		(property "Manufacturer" "Panasonic"
			(at 253.365 149.86 0)
			(effects
				(font
					(size 1.27 1.27)
					(thickness 0.15)
				)
				(justify left bottom)
				(hide yes)
			)
		)
		(property "MPN" "ERJ2GE0R00X"
			(at 253.365 147.32 0)
			(effects
				(font
					(size 1.27 1.27)
					(thickness 0.15)
				)
				(justify left bottom)
				(hide yes)
			)
		)
		(property "Val" "0R"
			(at 239.395 125.73 0)
			(effects
				(font
					(size 1.27 1.27)
					(thickness 0.15)
				)
			)
		)
		(property "License" "Apache-2.0"
			(at 253.365 152.4 0)
			(effects
				(font
					(size 1.27 1.27)
					(thickness 0.15)
				)
				(justify left bottom)
				(hide yes)
			)
		)
		(property "Author" "Antmicro"
			(at 253.365 154.94 0)
			(effects
				(font
					(size 1.27 1.27)
					(thickness 0.15)
				)
				(justify left bottom)
				(hide yes)
			)
		)
		(property "Tolerance" "~"
			(at 253.365 137.16 0)
			(effects
				(font
					(size 1.27 1.27)
				)
				(justify left bottom)
				(hide yes)
			)
		)
		(property "Current" "1A"
			(at 253.365 157.48 0)
			(effects
				(font
					(size 1.27 1.27)
					(thickness 0.15)
				)
				(justify left bottom)
				(hide yes)
			)
		)
		(pin "1"
		)
		(pin "2"
		)
		(instances
			(project "ddr5-testbed"
				(path ""
					(reference "R4")
					(unit 1)
				)
			)
		)
	)
	(symbol
		(lib_id "antmicroResistors0402:R_0R_0402")
		(at 233.045 132.08 0)
		(unit 1)
		(exclude_from_sim no)
		(in_bom yes)
		(on_board yes)
		(dnp no)
		(property "Reference" "R16"
			(at 230.505 130.81 0)
			(effects
				(font
					(size 1.27 1.27)
				)
			)
		)
		(property "Value" "R_0R_0402"
			(at 253.365 144.78 0)
			(effects
				(font
					(size 1.27 1.27)
					(thickness 0.15)
				)
				(justify left bottom)
				(hide yes)
			)
		)
		(property "Footprint" "antmicro-footprints:R_0402_1005Metric"
			(at 253.365 147.32 0)
			(effects
				(font
					(size 1.27 1.27)
					(thickness 0.15)
				)
				(justify left bottom)
				(hide yes)
			)
		)
		(property "Datasheet" "https://industrial.panasonic.com/cdbs/www-data/pdf/RDA0000/AOA0000C301.pdf"
			(at 253.365 149.86 0)
			(effects
				(font
					(size 1.27 1.27)
					(thickness 0.15)
				)
				(justify left bottom)
				(hide yes)
			)
		)
		(property "Description" ""
			(at 233.045 132.08 0)
			(effects
				(font
					(size 1.27 1.27)
				)
			)
		)
		(property "Manufacturer" "Panasonic"
			(at 253.365 154.94 0)
			(effects
				(font
					(size 1.27 1.27)
					(thickness 0.15)
				)
				(justify left bottom)
				(hide yes)
			)
		)
		(property "MPN" "ERJ2GE0R00X"
			(at 253.365 152.4 0)
			(effects
				(font
					(size 1.27 1.27)
					(thickness 0.15)
				)
				(justify left bottom)
				(hide yes)
			)
		)
		(property "Val" "0R"
			(at 239.395 130.81 0)
			(effects
				(font
					(size 1.27 1.27)
					(thickness 0.15)
				)
			)
		)
		(property "License" "Apache-2.0"
			(at 253.365 157.48 0)
			(effects
				(font
					(size 1.27 1.27)
					(thickness 0.15)
				)
				(justify left bottom)
				(hide yes)
			)
		)
		(property "Author" "Antmicro"
			(at 253.365 160.02 0)
			(effects
				(font
					(size 1.27 1.27)
					(thickness 0.15)
				)
				(justify left bottom)
				(hide yes)
			)
		)
		(property "Tolerance" "~"
			(at 253.365 142.24 0)
			(effects
				(font
					(size 1.27 1.27)
				)
				(justify left bottom)
				(hide yes)
			)
		)
		(property "Current" "1A"
			(at 253.365 162.56 0)
			(effects
				(font
					(size 1.27 1.27)
					(thickness 0.15)
				)
				(justify left bottom)
				(hide yes)
			)
		)
		(pin "1"
		)
		(pin "2"
		)
		(instances
			(project "ddr5-testbed"
				(path ""
					(reference "R16")
					(unit 1)
				)
			)
		)
	)
	(symbol
		(lib_id "antmicroResistors0402:R_0R_0402")
		(at 233.045 129.54 0)
		(unit 1)
		(exclude_from_sim no)
		(in_bom yes)
		(on_board yes)
		(dnp no)
		(property "Reference" "R15"
			(at 230.505 128.27 0)
			(effects
				(font
					(size 1.27 1.27)
				)
			)
		)
		(property "Value" "R_0R_0402"
			(at 253.365 142.24 0)
			(effects
				(font
					(size 1.27 1.27)
					(thickness 0.15)
				)
				(justify left bottom)
				(hide yes)
			)
		)
		(property "Footprint" "antmicro-footprints:R_0402_1005Metric"
			(at 253.365 144.78 0)
			(effects
				(font
					(size 1.27 1.27)
					(thickness 0.15)
				)
				(justify left bottom)
				(hide yes)
			)
		)
		(property "Datasheet" "https://industrial.panasonic.com/cdbs/www-data/pdf/RDA0000/AOA0000C301.pdf"
			(at 253.365 147.32 0)
			(effects
				(font
					(size 1.27 1.27)
					(thickness 0.15)
				)
				(justify left bottom)
				(hide yes)
			)
		)
		(property "Description" ""
			(at 233.045 129.54 0)
			(effects
				(font
					(size 1.27 1.27)
				)
			)
		)
		(property "Manufacturer" "Panasonic"
			(at 253.365 152.4 0)
			(effects
				(font
					(size 1.27 1.27)
					(thickness 0.15)
				)
				(justify left bottom)
				(hide yes)
			)
		)
		(property "MPN" "ERJ2GE0R00X"
			(at 253.365 149.86 0)
			(effects
				(font
					(size 1.27 1.27)
					(thickness 0.15)
				)
				(justify left bottom)
				(hide yes)
			)
		)
		(property "Val" "0R"
			(at 239.395 128.27 0)
			(effects
				(font
					(size 1.27 1.27)
					(thickness 0.15)
				)
			)
		)
		(property "License" "Apache-2.0"
			(at 253.365 154.94 0)
			(effects
				(font
					(size 1.27 1.27)
					(thickness 0.15)
				)
				(justify left bottom)
				(hide yes)
			)
		)
		(property "Author" "Antmicro"
			(at 253.365 157.48 0)
			(effects
				(font
					(size 1.27 1.27)
					(thickness 0.15)
				)
				(justify left bottom)
				(hide yes)
			)
		)
		(property "Tolerance" "~"
			(at 253.365 139.7 0)
			(effects
				(font
					(size 1.27 1.27)
				)
				(justify left bottom)
				(hide yes)
			)
		)
		(property "Current" "1A"
			(at 253.365 160.02 0)
			(effects
				(font
					(size 1.27 1.27)
					(thickness 0.15)
				)
				(justify left bottom)
				(hide yes)
			)
		)
		(pin "1"
		)
		(pin "2"
		)
		(instances
			(project "ddr5-testbed"
				(path ""
					(reference "R15")
					(unit 1)
				)
			)
		)
	)
)
